G04 ================== begin FILE IDENTIFICATION RECORD ==================*
G04 Layout Name:  15105-sa.brd*
G04 Film Name:    L6*
G04 File Format:  Gerber RS274X*
G04 File Origin:  Cadence Allegro 16.5-S056*
G04 Origin Date:  Wed Nov 16 02:02:24 2016*
G04 *
G04 Layer:  VIA CLASS/L6*
G04 Layer:  PIN/L6*
G04 Layer:  ETCH/L6*
G04 Layer:  DRAWING FORMAT/LAYER_PCB_STORY*
G04 Layer:  DRAWING FORMAT/LAYER_L6*
G04 *
G04 Offset:    (0.00 0.00)*
G04 Mirror:    No*
G04 Mode:      Positive*
G04 Rotation:  0*
G04 FullContactRelief:  No*
G04 UndefLineWidth:     6.00*
G04 ================== end FILE IDENTIFICATION RECORD ====================*
%FSLAX35Y35*MOIN*%
%IR0*IPPOS*OFA0.00000B0.00000*MIA0B0*SFA1.00000B1.00000*%
%ADD10C,.02*%
%ADD14C,.036*%
%ADD11C,.018*%
%ADD12C,.028*%
%ADD16C,.029*%
%ADD13C,.056*%
%ADD15C,.103*%
%ADD17C,.01*%
%ADD18C,.012*%
%ADD19C,.04*%
%ADD20C,.015*%
%ADD21C,.004*%
%ADD22C,.006*%
%ADD23C,.005*%
%ADD24C,.0053*%
%ADD25C,.0055*%
%ADD37C,.06004*%
%ADD38C,.08004*%
%ADD34C,.02604*%
%ADD32C,.04404*%
%ADD35C,.02704*%
%ADD31C,.09004*%
%ADD33C,.02804*%
%ADD26C,.11004*%
%ADD29C,.3151*%
%ADD27C,.15204*%
%ADD28C,.31532*%
%ADD36C,.31506*%
%ADD30C,.31534*%
G75*
%LPD*%
G75*
G36*
G01X486762Y-16681D02*
G02X481892Y-11811I0J4870D01*
G01Y-7874D01*
G03X471014Y3004I-10878J0D01*
G01X212402D01*
G02X207532Y7874I0J4870D01*
G01Y94528D01*
G03X196654Y105406I-10878J0D01*
G01X7874D01*
G02X3004Y110276I0J4870D01*
G01Y836614D01*
G02X3937Y837547I933J0D01*
G01X100000D01*
G03X101210Y837638I-2J8122D01*
G02X101670Y837243I60J-395D01*
G01Y832658D01*
G02X100000Y832551I-1672J13011D01*
G01X8000D01*
Y364576D01*
X14048Y358528D01*
Y303678D01*
X15176Y302550D01*
Y220228D01*
X23820Y211584D01*
X24629D01*
X28895Y207318D01*
X28958D01*
X30021Y206255D01*
X61926D01*
X62519Y206848D01*
X64469D01*
X65093Y206224D01*
X97599D01*
X98784Y205039D01*
Y193797D01*
X104182Y188399D01*
Y165838D01*
X120263Y149757D01*
G02X120106Y149094I-282J-283D01*
G03X128385Y140815I2059J-6220D01*
G02X129048Y140972I380J-125D01*
G01X132033Y137987D01*
X169533D01*
G03X178261I4364J4887D01*
G01X198573D01*
X217705Y118855D01*
Y98505D01*
X219622Y96588D01*
X226812D01*
X226845Y96576D01*
G03X228367I761J2066D01*
G01X228400Y96588D01*
X255964D01*
G03X256539Y95732I2065J766D01*
G02X256550Y95153I-271J-295D01*
G03X259590Y95210I1550J-1564D01*
G02X259579Y95789I271J295D01*
G03X260094Y96588I-1550J1564D01*
G01X263262D01*
X288596Y121922D01*
X354979D01*
G03X355159I90J2200D01*
G01X358827D01*
G03X358887Y121920I103J2200D01*
G01X358968Y121919D01*
X473013Y7874D01*
G02X486884Y-7523I-1999J-15748D01*
G01X486638Y-7769D01*
Y-7977D01*
X486784Y-8123D01*
X486888D01*
Y-11685D01*
X492813D01*
Y-16681D01*
X486762D01*
G37*
G36*
G01X64109Y451469D02*
X63500Y452078D01*
Y459900D01*
X65000Y461400D01*
X66700D01*
X71000Y465700D01*
X87490D01*
G03X91510I2010J900D01*
G01X95048D01*
G03X99152I2052J800D01*
G01X119200D01*
X135500Y482000D01*
Y484940D01*
X135510Y484970D01*
G03Y485778I-1238J404D01*
G01X135500Y485808D01*
Y488090D01*
X135510Y488120D01*
G03Y488928I-1238J404D01*
G01X135500Y488958D01*
Y490900D01*
G03X135572Y491029I-1230J771D01*
G02X136281Y491045I359J-177D01*
G03Y492303I1140J629D01*
G02X135572Y492319I-350J193D01*
G03X135500Y492448I-1302J-642D01*
G01Y503844D01*
X135510Y503874D01*
G03Y504670I-1240J398D01*
G01X135500Y504700D01*
Y505500D01*
X133500Y507500D01*
Y512000D01*
X136000Y514500D01*
Y518500D01*
X133000Y521500D01*
Y524500D01*
X136500Y528000D01*
X141500D01*
X144000Y530500D01*
X147200D01*
X147700Y530000D01*
Y527700D01*
X142200Y522200D01*
Y511700D01*
X145500Y508400D01*
X159400D01*
X163100Y512100D01*
Y524300D01*
X164300Y525500D01*
X169000D01*
X170500Y524000D01*
Y518093D01*
G02X169822Y517805I-400J0D01*
G03Y515935I-906J-935D01*
G02X170500Y515647I278J-288D01*
G01Y508000D01*
X167500Y505000D01*
Y503700D01*
X170000Y501200D01*
Y476800D01*
X150000Y456800D01*
X137663D01*
X137635Y456808D01*
G03X136365I-635J-2108D01*
G01X136337Y456800D01*
X133663D01*
X133635Y456808D01*
G03X132365I-635J-2108D01*
G01X132337Y456800D01*
X116163D01*
X116135Y456808D01*
G03X114865I-635J-2108D01*
G01X114837Y456800D01*
X112163D01*
X112135Y456808D01*
G03X110865I-635J-2108D01*
G01X110837Y456800D01*
X104163D01*
X104135Y456808D01*
G03X102865I-635J-2108D01*
G01X102837Y456800D01*
X93800D01*
X93445Y457155D01*
X93431Y457205D01*
G03X89604Y458000I-2120J-596D01*
G01X86500D01*
X79969Y451469D01*
X64109D01*
G37*
G36*
G01X592648Y334126D02*
X588220Y338553D01*
X549096D01*
X539862Y347787D01*
X537926D01*
X535461Y350252D01*
X517430D01*
X517402Y350280D01*
Y378398D01*
X477500Y418300D01*
X453642D01*
X435172Y436770D01*
X432539D01*
X337778Y531530D01*
X322642D01*
X322598Y531670D01*
G03X319330Y529135I-2098J-670D01*
G02X319407Y528520I-213J-339D01*
G03X323139Y526475I1593J-1520D01*
G01X323176Y526628D01*
X335747D01*
X430630Y431744D01*
Y428382D01*
X396945Y394697D01*
X328639D01*
X303592Y419744D01*
Y442504D01*
G03X301136Y446120I-1451J1656D01*
G02X300554Y446476I-182J356D01*
G01Y454024D01*
X300652Y454122D01*
Y456690D01*
G02X301068Y457090I400J1D01*
G03X302799Y460763I94J2200D01*
G02X302800Y461299I297J267D01*
G03X303251Y463499I-1630J1480D01*
G02X303731Y464017I378J131D01*
G03X304139Y463949I564J2129D01*
G02X304325Y463735I-13J-199D01*
G03X306675Y465773I2196J-159D01*
G02X306489Y465987I13J199D01*
G03X302212Y465427I-2196J159D01*
G02X301732Y464909I-378J-131D01*
G03X301070Y464980I-563J-2129D01*
G02X300652Y465379I-18J399D01*
G01Y488567D01*
X298174Y491045D01*
Y503701D01*
X298171Y503704D01*
Y504031D01*
X293352Y508850D01*
Y519298D01*
G02X294078Y519529I400J0D01*
G03Y522071I1798J1271D01*
G02X293352Y522302I-326J231D01*
G01Y541054D01*
X302132Y549834D01*
Y569810D01*
X291129Y580813D01*
G02X291170Y581414I283J283D01*
G03X288084Y584500I-1335J1751D01*
G02X287483Y584459I-318J242D01*
G01X247202Y624740D01*
Y625000D01*
X246200Y626002D01*
Y663169D01*
X257361Y674330D01*
X283019D01*
X305333Y674204D01*
X305340D01*
G03X305635Y674202I162J2196D01*
G01X305642Y674203D01*
X374626Y673814D01*
X457279Y629388D01*
X485519Y588405D01*
X556292Y534854D01*
X615182Y465631D01*
X664085Y409496D01*
X665291Y408290D01*
Y365156D01*
X644764Y344629D01*
G02X644488Y344623I-141J142D01*
G03X641377Y341512I-1488J-1623D01*
G02X641371Y341236I-148J-135D01*
G01X638688Y338553D01*
X609793D01*
X607359Y336119D01*
Y336087D01*
X605398Y334126D01*
X592648D01*
G37*
G36*
G01X455118Y832551D02*
G02X442000Y845669I0J13118D01*
G01Y866061D01*
X446996D01*
Y845669D01*
G03X455118Y837547I8122J0D01*
G01X517323D01*
G03X525445Y845669I0J8122D01*
G01Y866061D01*
X530441D01*
Y845669D01*
G02X528173Y838297I-13118J1D01*
G03X525457Y835378I-673J-2097D01*
G02X517323Y832551I-8135J10291D01*
G01X502741D01*
G03X498873I-1934J-1052D01*
G01X455118D01*
G37*
G36*
G01X1050835Y640581D02*
X1031549Y522800D01*
X1031205D01*
X1020528Y512123D01*
X1007097D01*
X943729Y575491D01*
X915317Y623705D01*
X915164Y627336D01*
X913819Y628681D01*
Y820866D01*
G03X902134Y832551I-11685J0D01*
G01X872441D01*
G02X859323Y845669I0J13118D01*
G01Y861303D01*
X864319D01*
Y845669D01*
G03X872441Y837547I8122J0D01*
G01X902134D01*
G02X918815Y820866I0J-16681D01*
G01Y650669D01*
G03X926819Y642665I8004J0D01*
G01X983748D01*
G03X991752Y650669I0J8004D01*
G01Y820866D01*
G02X1008433Y837547I16681J0D01*
G01X1013386D01*
G03X1021508Y845669I0J8122D01*
G01Y858625D01*
X1026504D01*
Y845669D01*
G02X1023973Y837923I-13118J0D01*
G01Y752163D01*
X1025006Y751130D01*
X1042569Y683629D01*
X1050835Y640581D01*
G37*
G36*
G01X953768Y100773D02*
X957748Y96792D01*
Y96791D01*
X961374Y93165D01*
Y82191D01*
X959835Y80652D01*
X947599D01*
X947597Y80650D01*
X945350D01*
X935002Y70302D01*
X917598D01*
X916400Y71500D01*
Y71800D01*
X927100Y82500D01*
Y83281D01*
G03X928142Y84433I-1007J1958D01*
G02X928402Y84546I186J-73D01*
G03X927763Y88250I811J2047D01*
G02X927100Y88551I-263J301D01*
G01Y94698D01*
G03X928555Y98553I0J2202D01*
G02X928536Y99136I264J300D01*
G01X936000Y106600D01*
Y112800D01*
X938600Y115400D01*
Y115514D01*
X938620Y115555D01*
G03Y116729I-1218J587D01*
G01X938600Y116770D01*
Y119451D01*
X938620Y119492D01*
G03Y120666I-1218J587D01*
G01X938600Y120707D01*
Y123388D01*
X938620Y123429D01*
G03Y124603I-1218J587D01*
G01X938600Y124644D01*
Y125100D01*
X938100Y125600D01*
X937100D01*
X936000Y126700D01*
Y128400D01*
X938100Y130500D01*
Y130732D01*
G03Y133048I-698J1158D01*
G01Y134669D01*
G03X936774Y137024I-699J1157D01*
G01X936644Y136956D01*
X936000Y137600D01*
Y140500D01*
X936500Y141000D01*
X939500D01*
X940000Y140500D01*
Y139956D01*
X939998Y139943D01*
G03Y139585I1341J-179D01*
G01X940000Y139572D01*
Y136243D01*
X939992Y136216D01*
G03X939977Y136155I1353J-365D01*
G03X939938Y135827I1362J-328D01*
G01Y134458D01*
G03X939994Y133998I1901J-2D01*
G01X940000Y133974D01*
Y133142D01*
X939994Y133118D01*
G03X939938Y132658I1845J-458D01*
G01Y131890D01*
G03X942236Y130813I1401J0D01*
G03X942605Y131288I-896J1077D01*
G01X942620Y131320D01*
X943056Y131756D01*
X943450D01*
G03X946152Y134458I0J2702D01*
G01Y143669D01*
X946402Y143919D01*
Y144136D01*
X946411Y144165D01*
G03X946419Y144190I-1402J462D01*
G03X946476Y144600I-1420J406D01*
G01Y160476D01*
X948000Y162000D01*
X974500D01*
X975500Y161000D01*
Y159909D01*
X975490Y159878D01*
G03Y159020I1281J-429D01*
G01X975500Y158989D01*
Y158500D01*
X975000Y158000D01*
X970500D01*
X969934Y158566D01*
X970024Y158702D01*
G03X968047Y160500I-1127J747D01*
G01X967209D01*
X967208Y160502D01*
X965809D01*
G03X964111I-849J-1053D01*
G01X961872D01*
G03X960174I-849J-1053D01*
G01X957935D01*
G03X956237I-849J-1053D01*
G01X954292D01*
X954291Y160500D01*
X954002D01*
X953949Y160539D01*
G03X952500Y158263I-800J-1090D01*
G01Y156698D01*
G03X952792Y154208I649J-1186D01*
G01X954000Y153000D01*
Y149552D01*
X953998Y149549D01*
Y149498D01*
X952500Y148000D01*
Y144887D01*
G03Y142515I649J-1186D01*
G01Y140950D01*
G03Y138578I649J-1186D01*
G01Y137013D01*
G03X952148Y134918I649J-1186D01*
G01X952277Y134777D01*
X950500Y133000D01*
Y132763D01*
X946748Y129011D01*
Y128948D01*
X946700Y128900D01*
Y102079D01*
X948006Y100773D01*
X953768D01*
G37*
G36*
G01X928126Y154491D02*
X928500Y154118D01*
Y152453D01*
G03Y150697I1028J-878D01*
G01Y150000D01*
X928000Y149500D01*
X923500D01*
X922500Y150500D01*
Y150520D01*
G03Y152630I-846J1055D01*
G01Y154457D01*
G03Y156567I-846J1055D01*
G01Y158394D01*
G03Y160504I-846J1055D01*
G01Y161500D01*
X923500Y162500D01*
X924570D01*
G03X926612I1021J886D01*
G01X928507D01*
G03X930549I1021J886D01*
G01X932444D01*
G03X934486I1021J886D01*
G01X936381D01*
G03X937357Y162035I1021J886D01*
G02X937550Y161835I-7J-200D01*
G01Y157550D01*
X936602Y156602D01*
X936591Y156593D01*
G03X936479Y156500I806J-1085D01*
G01X934388D01*
G03X932542I-923J-988D01*
G01X930522D01*
G03X928126Y155512I-994J-988D01*
G01Y154491D01*
G37*
G36*
G01X974039Y164000D02*
G03X971629I-1205J-614D01*
G01X970102D01*
G03X967692I-1205J-614D01*
G01X966165D01*
G03X963755I-1205J-614D01*
G01X962228D01*
G03X959818I-1205J-614D01*
G01X958291D01*
G03X955735Y163327I-1205J-613D01*
G01X955739Y163239D01*
X955002Y162502D01*
X951498D01*
X950565Y163435D01*
X950559Y163507D01*
G03X950508Y163770I-1346J-125D01*
G01X950500Y163798D01*
Y166911D01*
X950508Y166939D01*
G03Y167707I-1296J384D01*
G01X950500Y167735D01*
Y169500D01*
X950200Y169800D01*
Y170337D01*
G03Y172183I-988J923D01*
G01Y174274D01*
G03Y176120I-988J923D01*
G01Y178211D01*
G03Y180057I-988J923D01*
G01Y182148D01*
G03Y183994I-988J923D01*
G01Y187300D01*
X945600Y191900D01*
X942295D01*
G03X940383I-956J-956D01*
G01X938358D01*
G03X936446I-956J-956D01*
G01X934421D01*
G03X932509I-956J-956D01*
G01X930484D01*
G03X928572I-956J-956D01*
G01X926547D01*
G03X924635I-956J-956D01*
G01X922610D01*
G03X920698I-956J-956D01*
G01X918673D01*
G03X916761I-956J-956D01*
G01X914736D01*
G03X912878Y191951I-956J-956D01*
G01X912821Y191900D01*
X912400D01*
X911100Y193200D01*
Y194382D01*
X911112Y194415D01*
G03Y195347I-1269J466D01*
G01X911100Y195380D01*
Y198319D01*
X911112Y198352D01*
G03Y199284I-1269J466D01*
G01X911100Y199317D01*
Y202256D01*
X911112Y202289D01*
G03Y203221I-1269J466D01*
G01X911100Y203254D01*
Y206193D01*
X911112Y206226D01*
G03Y207158I-1269J466D01*
G01X911100Y207191D01*
Y210130D01*
X911112Y210163D01*
G03Y211095I-1269J466D01*
G01X911100Y211128D01*
Y214042D01*
G03X911135Y214135I-1256J526D01*
G01X912500Y215500D01*
X914500D01*
X916500Y213500D01*
X916883D01*
X916935Y213463D01*
G03X918549Y213500I782J1103D01*
G01X920822D01*
G03X922486I832J1066D01*
G01X924759D01*
G03X926423I832J1066D01*
G01X928696D01*
G03X930360I832J1066D01*
G01X932633D01*
G03X934297I832J1066D01*
G01X936570D01*
G03X938234I832J1066D01*
G01X940507D01*
G03X942171I832J1066D01*
G01X948380D01*
G03X950044I832J1066D01*
G01X952317D01*
G03X953981I832J1066D01*
G01X956254D01*
G03X957918I832J1066D01*
G01X960191D01*
G03X961855I832J1066D01*
G01X964128D01*
G03X965792I832J1066D01*
G01X968065D01*
G03X969729I832J1066D01*
G01X972002D01*
G03X973666I832J1066D01*
G01X975939D01*
G03X977553Y213463I832J1066D01*
G01X977605Y213500D01*
X978000D01*
X979500Y215000D01*
X983000D01*
X983297Y214703D01*
X983294Y214616D01*
G03X983500Y213847I1351J-50D01*
G01Y211348D01*
G03Y209910I1145J-719D01*
G01Y207411D01*
G03Y205973I1145J-719D01*
G01Y203474D01*
G03Y202036I1145J-719D01*
G01Y199537D01*
G03Y198099I1145J-719D01*
G01Y195600D01*
G03Y194162I1145J-719D01*
G01Y191663D01*
G03Y190225I1145J-719D01*
G01Y183790D01*
G03Y182352I1145J-719D01*
G01Y179853D01*
G03Y178415I1145J-719D01*
G01Y175916D01*
G03Y174478I1145J-719D01*
G01Y171979D01*
G03Y170541I1145J-719D01*
G01Y168042D01*
G03Y166604I1145J-719D01*
G01Y165000D01*
X982500Y164000D01*
X981913D01*
G03X979503I-1205J-614D01*
G01X977976D01*
G03X975566I-1205J-614D01*
G01X974039D01*
G37*
G36*
G01X969046Y151637D02*
Y149189D01*
G02X968852Y148989I-200J0D01*
G03X967855Y148500I44J-1351D01*
G01X966002D01*
G03X963918I-1042J-862D01*
G01X962065D01*
G03X961085Y148989I-1042J-862D01*
G01X961008Y148992D01*
X958440Y151560D01*
X958437Y151637D01*
G03X957148Y152926I-1351J-62D01*
G01X957071Y152929D01*
X954503Y155497D01*
X954500Y155574D01*
G03X954000Y156563I-1351J-62D01*
G01Y158398D01*
G03X954496Y159566I-851J1051D01*
G02X954894Y160000I398J34D01*
G01X959278D01*
G02X959676Y159566I0J-400D01*
G03X962370I1347J-117D01*
G02X962768Y160000I398J34D01*
G01X967000D01*
X967543Y159457D01*
X967547Y159380D01*
G03X968000Y158437I1350J68D01*
G01Y156653D01*
G03X967446Y155512I898J-1141D01*
G01Y153237D01*
X969046Y151637D01*
G37*
G36*
G01X1047077Y-16681D02*
Y-11685D01*
X1052743D01*
G03X1056245I1751J2560D01*
G01X1075983D01*
X1131078Y43410D01*
X1134394D01*
G02X1134626Y42685I-1J-400D01*
G03X1142022I3698J-5165D01*
G02X1142254Y43410I233J325D01*
G01X1177701D01*
G02X1177933Y42685I-1J-400D01*
G03X1185329I3698J-5165D01*
G02X1185561Y43410I233J325D01*
G01X1221009D01*
G02X1221241Y42685I-1J-400D01*
G03X1228637I3698J-5165D01*
G02X1228869Y43410I233J325D01*
G01X1264316D01*
G02X1264548Y42685I-1J-400D01*
G03X1271944I3698J-5165D01*
G02X1272176Y43410I233J325D01*
G01X1292595D01*
X1296728Y47543D01*
Y114354D01*
X1318769Y136395D01*
X1344529D01*
G02X1344929Y135991I0J-400D01*
G03X1374255Y143629I15701J-165D01*
G01X1374179Y143762D01*
X1392000Y161583D01*
Y272084D01*
X1391780D01*
X1344432Y319432D01*
X1344500Y319500D01*
X1327000Y337000D01*
Y383500D01*
X1313000Y397500D01*
X1308000D01*
X1306500Y396000D01*
Y389000D01*
X1312500Y383000D01*
Y338000D01*
X1311000Y336500D01*
X1274000D01*
X1272000Y338500D01*
X1268500D01*
X1268000Y338000D01*
Y335000D01*
X1255365Y322365D01*
X1183080D01*
X1174814Y330631D01*
Y384010D01*
X1175159Y384355D01*
X1217174Y619056D01*
X1258700Y680900D01*
X1288732Y725256D01*
G02X1289427Y725199I331J-224D01*
G03X1291537Y728316I2001J918D01*
G02X1291226Y728940I20J400D01*
G01X1295600Y735400D01*
X1346335Y793480D01*
G02X1346983Y793415I301J-263D01*
G03X1360957Y816879I13647J7766D01*
G01Y834939D01*
G02X1355386Y845668I7547J10730D01*
G01Y858625D01*
X1360382D01*
Y845669D01*
G03X1368504Y837547I8122J0D01*
G01X1396063D01*
G02X1396996Y836614I0J-933D01*
G01Y77025D01*
G02X1396600Y76626I-400J1D01*
G03X1391681Y71654I54J-4972D01*
G01Y40157D01*
G03X1396600Y35185I4973J0D01*
G02X1396996Y34786I-4J-400D01*
G01Y4596D01*
X1395800Y3400D01*
X1307500D01*
X1303000Y-1100D01*
Y-15481D01*
X1301800Y-16681D01*
X1047077D01*
G37*
G36*
G01X1323500Y337500D02*
X1390798Y270202D01*
Y175798D01*
X1389880Y174880D01*
G02X1389228Y175009I-283J283D01*
G03X1386347Y172128I-2032J-849D01*
G02X1386476Y171476I-154J-369D01*
G01X1376700Y161700D01*
X1352791D01*
X1352779Y161888D01*
G03X1344791I-3994J-246D01*
G01X1344779Y161700D01*
X1327201D01*
X1327189Y161888D01*
G03X1320654Y164734I-3994J-246D01*
G02X1320000Y165043I-254J309D01*
G01Y175957D01*
G02X1320654Y176266I400J0D01*
G03Y182450I2541J3092D01*
G02X1320000Y182759I-254J309D01*
G01Y182900D01*
X1321850Y184750D01*
X1363643D01*
X1363683Y184604D01*
G03X1367925I2121J593D01*
G01X1367965Y184750D01*
X1384250D01*
X1385500Y186000D01*
Y259500D01*
X1365791Y279209D01*
X1365874Y279344D01*
G03X1362844Y282374I-1874J1156D01*
G01X1362709Y282291D01*
X1316500Y328500D01*
X1271500D01*
X1269000Y331000D01*
Y334301D01*
X1269202Y334502D01*
Y336201D01*
X1270000Y337000D01*
X1271500D01*
X1273500Y335000D01*
X1311500D01*
X1314000Y337500D01*
Y384000D01*
X1308000Y390000D01*
Y395000D01*
X1309000Y396000D01*
X1312801D01*
X1323500Y385301D01*
Y337500D01*
G37*
%LPC*%
G75*
G36*
G01X365945Y76624D02*
G02X370914Y71654I-1J-4970D01*
G01Y40157D01*
G02X365945Y35188I-4969J0D01*
G01X356102D01*
G02X351132Y40157I0J4970D01*
G01Y71654D01*
G02X356102Y76624I4970J0D01*
G01X365945D01*
G37*
G36*
G01X101301Y151622D02*
Y151524D01*
X101297Y151430D01*
G02Y151808I-5108J189D01*
G01X101300Y151716D01*
X101301Y151624D01*
Y151622D01*
G37*
G36*
G01X32089D02*
Y151524D01*
X32085Y151430D01*
G02Y151808I-5108J189D01*
G01X32088Y151716D01*
X32089Y151624D01*
Y151622D01*
G37*
G36*
G01X73231Y186422D02*
G02Y188774I-3616J1176D01*
G03X73991I380J123D01*
G02X81223I3616J-1176D01*
G03X81983I380J123D01*
G02Y186422I3616J-1176D01*
G03X81223I-380J-123D01*
G02X73991I-3616J1176D01*
G03X73231I-380J-123D01*
G37*
G36*
G01X41183D02*
G02Y188774I-3616J1176D01*
G03X41943I380J123D01*
G02X49175I3616J-1176D01*
G03X49935I380J123D01*
G02Y186422I3616J-1176D01*
G03X49175I-380J-123D01*
G02X41943I-3616J1176D01*
G03X41183I-380J-123D01*
G37*
G36*
G01X45219Y176422D02*
G02Y178774I-3616J1176D01*
G03X45979I380J123D01*
G02X53211I3616J-1176D01*
G03X53971I380J123D01*
G02X61203I3616J-1176D01*
G03X61963I380J123D01*
G02X69195I3616J-1176D01*
G03X69955I380J123D01*
G02X77187I3616J-1176D01*
G03X77947I380J123D01*
G02Y176422I3616J-1176D01*
G03X77187I-380J-123D01*
G02X69955I-3616J1176D01*
G03X69195I-380J-123D01*
G02X61963I-3616J1176D01*
G03X61203I-380J-123D01*
G02X53971I-3616J1176D01*
G03X53211I-380J-123D01*
G02X45979I-3616J1176D01*
G03X45219I-380J-123D01*
G37*
G36*
G01X313058Y549556D02*
G03X313342I142J141D01*
G02Y546444I1558J-1556D01*
G03X313058I-142J-141D01*
G02Y549556I-1558J1556D01*
G37*
G36*
G01X327798Y501898D02*
G03X327597Y502098I-200J0D01*
G02X329791Y504302I-8J2202D01*
G03X329992Y504102I200J0D01*
G02X327798Y501898I8J-2202D01*
G37*
G36*
G01X323528Y461578D02*
G03X323516Y461295I135J-147D01*
G02X320408Y461420I-1617J-1495D01*
G03X320420Y461703I-135J147D01*
G02X320591Y464859I1616J1495D01*
G03X320610Y465142I-131J151D01*
G02X320730Y468166I1658J1449D01*
G03X320733Y468449I-140J143D01*
G02X323843Y468416I1572J1542D01*
G03X323840Y468133I140J-143D01*
G02X323713Y464930I-1572J-1542D01*
G03X323694Y464647I131J-151D01*
G02X323528Y461578I-1658J-1449D01*
G37*
G36*
G01X314470Y432145D02*
G03X314471Y431468I214J-338D01*
G02X312124Y431464I-1170J-1865D01*
G03X312123Y432141I-214J338D01*
G02X311836Y435656I1171J1865D01*
G03X311853Y435939I-133J150D01*
G02X311910Y438923I1647J1461D01*
G03Y439477I-289J277D01*
G02X315090I1590J1523D01*
G03Y438923I289J-277D01*
G02X314958Y435750I-1590J-1523D01*
G03X314941Y435467I133J-150D01*
G02X314470Y432145I-1647J-1461D01*
G37*
G36*
G01X617688Y420350D02*
G03X618241Y420028I397J46D01*
G02X616912Y417750I859J-2028D01*
G03X616359Y418072I-397J-46D01*
G02X617688Y420350I-859J2028D01*
G37*
G36*
G01X559469Y389782D02*
G03X559768Y390262I-91J390D01*
G02X562416Y388618I2145J500D01*
G03X562117Y388138I91J-390D01*
G02X559469Y389782I-2145J-500D01*
G37*
G36*
G01X540617Y378946D02*
G03Y378279I221J-333D01*
G02X538183I-1217J-1835D01*
G03Y378946I-221J334D01*
G02X540617I1217J1835D01*
G37*
G36*
G01X622559Y342434D02*
G03X622155Y341952I-13J-400D01*
G02X618227Y340194I-2155J-452D01*
G03X617711Y340306I-322J-238D01*
G02X618413Y343536I-1071J1924D01*
G03X618929Y343424I322J238D01*
G02X620070Y343701I1071J-1924D01*
G03X620474Y344183I13J400D01*
G02X622559Y342434I2155J452D01*
G37*
G36*
G01X599696Y339776D02*
G03X600187Y339515I380J123D01*
G02X598704Y336724I613J-2115D01*
G03X598213Y336985I-380J-123D01*
G02X599696Y339776I-613J2115D01*
G37*
G36*
G01X561154Y371699D02*
X561240Y371701D01*
G02X559099Y369560I60J-2201D01*
G01X559101Y369646D01*
X557934Y370814D01*
X535934D01*
X535833Y370914D01*
G03X535155Y370692I-283J-283D01*
G02X532647Y373200I-2177J331D01*
G03X532869Y373878I-61J395D01*
G01X273598Y633149D01*
Y637529D01*
G03X272937Y637832I-400J0D01*
G02Y641168I-1437J1668D01*
G03X273598Y641471I261J303D01*
G01Y646649D01*
X269499Y650748D01*
X258256D01*
G02Y653652I-1656J1452D01*
G01X270701D01*
X276502Y647851D01*
Y634351D01*
X285571Y625282D01*
G03X286245Y625647I283J283D01*
G02X287947Y623945I2155J453D01*
G03X287582Y623271I-82J-391D01*
G01X537136Y373716D01*
X559136D01*
X561154Y371699D01*
G37*
G36*
G01X955342Y605444D02*
G03X955058I-142J-141D01*
G02Y608556I-1558J1556D01*
G03X955342I142J141D01*
G02X958423Y608590I1558J-1556D01*
G03X958977I277J289D01*
G02Y605410I1523J-1590D01*
G03X958423I-277J-289D01*
G02X955342Y605444I-1523J1590D01*
G37*
G36*
G01X936427Y87644D02*
G03X936694Y87550I180J86D01*
G02X935653Y84618I948J-1987D01*
G03X935386Y84712I-180J-86D01*
G02X936427Y87644I-948J1987D01*
G37*
G36*
G01X954995Y87199D02*
G03X955277Y87174I153J128D01*
G02X954993Y84076I1410J-1691D01*
G03X954711Y84101I-153J-128D01*
G02X954995Y87199I-1410J1691D01*
G37*
G36*
G01X1339906Y734171D02*
G03X1340501Y734113I323J236D01*
G02X1340222Y731201I1499J-1613D01*
G03X1339627Y731259I-323J-236D01*
G02X1336507Y731381I-1499J1613D01*
G03X1335893Y731350I-294J-271D01*
G02X1332435Y731258I-1765J1317D01*
G03X1331821I-307J-255D01*
G02Y734076I-1693J1409D01*
G03X1332435I307J255D01*
G02X1335749Y734158I1693J-1409D01*
G03X1336363Y734189I294J271D01*
G02X1339906Y734171I1765J-1317D01*
G37*
G36*
G01X1335807Y721591D02*
G03X1335193I-307J-255D01*
G02Y724409I-1693J1409D01*
G03X1335807I307J255D01*
G02Y721591I1693J-1409D01*
G37*
G36*
G01X1304585Y695800D02*
G03X1304200Y695415I15J-400D01*
G02X1301915Y697700I-2200J85D01*
G03X1302300Y698085I-15J400D01*
G02X1304585Y695800I2200J-85D01*
G37*
G36*
G01X1328935Y687010D02*
G03X1329163Y686843I198J31D01*
G02X1327323Y684335I337J-2176D01*
G03X1327095Y684502I-198J-31D01*
G02X1328935Y687010I-337J2176D01*
G37*
G36*
G01X1338832Y685976D02*
G03X1339094Y685867I185J76D01*
G02X1337897Y682997I840J-2035D01*
G03X1337635Y683106I-185J-76D01*
G02X1338832Y685976I-840J2035D01*
G37*
G36*
G01X1320347Y685865D02*
G03X1320874Y685732I335J218D01*
G02X1320081Y682600I1054J-1933D01*
G03X1319554Y682733I-335J-218D01*
G02X1316354Y684173I-1054J1934D01*
G03X1315816Y684455I-390J-90D01*
G02X1314751Y684312I-817J2045D01*
G03X1314311Y683973I-44J-397D01*
G02X1312381Y686481I-2179J320D01*
G03X1312821Y686820I44J397D01*
G02X1317146Y686994I2179J-320D01*
G03X1317684Y686712I390J90D01*
G02X1320347Y685865I816J-2045D01*
G37*
G36*
G01X1312049Y662444D02*
G03X1311765I-142J-141D01*
G02Y665556I-1558J1556D01*
G03X1312049I142J141D01*
G02X1315165I1558J-1556D01*
G03X1315449I142J141D01*
G02Y662444I1558J-1556D01*
G03X1315165I-142J-141D01*
G02X1312049I-1558J1556D01*
G37*
G36*
G01X1329471Y660415D02*
G03X1328887Y660385I-278J-287D01*
G02X1328729Y663385I-1687J1415D01*
G03X1329313Y663415I278J287D01*
G02X1329471Y660415I1687J-1415D01*
G37*
G36*
G01X1301727Y716802D02*
G03X1302126Y717202I-1J400D01*
G01Y730670D01*
G02X1303821Y734281I2J2202D01*
G03X1304435I307J255D01*
G02X1306130Y730670I1693J-1409D01*
G01Y703577D01*
X1297002Y694449D01*
Y679710D01*
G03X1297435Y679311I400J0D01*
G02Y674923I182J-2194D01*
G03X1297001Y674524I-34J-399D01*
G01Y666600D01*
G03X1297417Y666200I400J0D01*
G02Y661800I83J-2200D01*
G03X1297002Y661400I-15J-400D01*
G01Y653902D01*
G03X1297401Y653502I400J0D01*
G02X1295801Y649786I-1J-2202D01*
G01X1295742Y649848D01*
X1295687D01*
X1294098Y651437D01*
Y651463D01*
G03X1293757Y651604I-200J0D01*
G01X1292566Y650413D01*
X1292551Y650381D01*
G02X1291269Y653381I-2001J919D01*
G01X1291388Y653340D01*
X1292998Y654951D01*
Y696107D01*
X1302126Y705235D01*
Y711998D01*
G03X1301727Y712398I-400J0D01*
G02Y716802I1J2202D01*
G37*
G36*
G01X1283878Y385350D02*
G03X1283991Y384812I341J-209D01*
G02X1280862Y384150I-1251J-1812D01*
G03X1280749Y384688I-341J209D01*
G02X1283878Y385350I1251J1812D01*
G37*
G36*
G01X1291299Y385231D02*
G03X1291395Y384674I327J-230D01*
G02X1288326Y384144I-1270J-1799D01*
G03X1288230Y384701I-327J230D01*
G02X1291299Y385231I1270J1799D01*
G37*
G36*
G01X1295938Y383790D02*
G03X1295765Y384424I-306J257D01*
G02X1298187Y385085I735J2076D01*
G03X1298360Y384451I306J-257D01*
G02X1295938Y383790I-735J-2076D01*
G37*
G36*
G01X1283956Y348174D02*
G03X1283826Y347647I220J-334D01*
G02X1280684Y348416I-1926J-1067D01*
G03X1280814Y348943I-220J334D01*
G02X1283956Y348174I1926J1067D01*
G37*
G36*
G01X1312404Y721894D02*
G02Y724106I-1904J1106D01*
G03X1313096I346J201D01*
G02Y721894I1904J-1106D01*
G03X1312404I-346J-201D01*
G37*
G36*
G01X1198797Y416052D02*
G02X1198127Y417787I-2197J148D01*
G03X1198803Y418048I277J288D01*
G02X1199473Y416313I2197J-148D01*
G03X1198797Y416052I-277J-288D01*
G37*
G36*
G01X1277004Y346724D02*
G02X1275282Y347881I-1944J-1034D01*
G03X1275676Y348466I41J398D01*
G02X1277398Y347309I1944J1034D01*
G03X1277004Y346724I-41J-398D01*
G37*
G36*
G01X1383231Y182022D02*
G03X1383831Y182016I303J262D01*
G02X1383804Y179100I1636J-1473D01*
G03X1383204Y179106I-303J-262D01*
G02X1383231Y182022I-1636J1473D01*
G37*
G36*
G01X1356800Y168672D02*
G03X1357439Y168639I332J223D01*
G02X1357299Y166000I1689J-1413D01*
G03X1356660Y166033I-332J-223D01*
G02X1356800Y168672I-1689J1413D01*
G37*
G54D37*
X1116671Y-315D03*
X1159978D03*
X1203285D03*
X1246592D03*
X1289899D03*
G54D38*
X1348785Y179358D03*
G54D34*
X140571Y491674D03*
X140570Y488523D03*
X162618Y485374D03*
X150020Y491674D03*
X156319Y485374D03*
X146870Y491674D03*
Y482225D03*
X143721Y491674D03*
Y488524D03*
Y485374D03*
X146869Y494823D03*
X153168D03*
X159467D03*
X165768Y488524D03*
X153170Y491674D03*
X150020Y485374D03*
Y482225D03*
X146870Y485374D03*
Y488524D03*
X162618D03*
Y491674D03*
X165768D03*
X137421Y485374D03*
X140571D03*
X156318Y488523D03*
X156319Y491674D03*
X153169Y485374D03*
Y488524D03*
X159469Y491674D03*
Y488524D03*
Y485374D03*
X150020Y488524D03*
X137421D03*
G54D32*
X228163Y68589D03*
Y78589D03*
Y93589D03*
Y88589D03*
X257759Y68589D03*
X257731Y78589D03*
X260562Y85988D03*
X289835Y588165D03*
X297750Y592750D03*
X281800Y638900D03*
X288400Y634200D03*
X292500Y630200D03*
X329014Y472022D03*
X327512Y509612D03*
X303800Y505100D03*
X304400Y511400D03*
X333102Y485902D03*
X305500Y483550D03*
X306900Y529100D03*
X335570Y491460D03*
X534500Y395100D03*
X528850Y394750D03*
X552720Y364180D03*
X567150Y415750D03*
X560900Y413700D03*
X604400Y421200D03*
X579900Y427400D03*
X618600Y357100D03*
X609000Y390350D03*
X643000Y369500D03*
X648792Y358431D03*
X935000Y97400D03*
X942800Y85700D03*
X948200Y85900D03*
X949500Y97500D03*
X1272500Y350000D03*
X1264820Y349320D03*
X1249250Y390250D03*
X1269500Y397000D03*
X1273500Y400500D03*
X1258000Y421500D03*
X1303983Y22083D03*
X1304000Y44000D03*
Y67500D03*
Y90500D03*
X1293280Y345770D03*
X1289960Y349900D03*
X1299000Y347500D03*
X1301000Y618500D03*
X1300000Y637000D03*
X1286800Y671100D03*
X1302128Y685500D03*
X1307000Y686500D03*
X1326128Y674000D03*
X1340000D03*
X1334128D03*
X1337500Y698000D03*
X1322439Y697767D03*
X1314628Y733000D03*
X1325600Y722987D03*
X1340500Y742500D03*
X1351500Y675000D03*
X1368028Y175745D03*
G54D35*
X941339Y127953D03*
Y124016D03*
Y120079D03*
Y116142D03*
X949212Y139764D03*
Y155512D03*
Y151575D03*
Y143701D03*
Y147638D03*
X929528Y159449D03*
X933465D03*
X925591D03*
Y155512D03*
X921654Y194881D03*
X917717Y198818D03*
X937402Y194881D03*
X933465Y198818D03*
X929528Y202755D03*
X925591Y206692D03*
X921654Y210629D03*
X929528Y194881D03*
X925591Y198818D03*
X921654Y202755D03*
X917717Y206692D03*
X929528Y210629D03*
X933465Y206692D03*
X937402Y202755D03*
X941339Y198818D03*
X937402Y210629D03*
X941339Y206692D03*
X925591Y194881D03*
X921654Y198818D03*
X917717Y202755D03*
X933465Y210629D03*
X937402Y206692D03*
X941339Y202755D03*
Y194881D03*
X937402Y198818D03*
X933465Y202755D03*
X929528Y206692D03*
X925591Y210629D03*
X933465Y194881D03*
X929528Y198818D03*
X925591Y202755D03*
X921654Y206692D03*
X917717Y210629D03*
Y194881D03*
X913780D03*
Y198818D03*
Y202755D03*
Y206692D03*
Y210629D03*
X964960Y167323D03*
X957086Y175197D03*
X961023Y171260D03*
X953149D03*
X957086Y167323D03*
X972834D03*
X968897Y171260D03*
X964960Y175197D03*
X972834D03*
X953149Y167323D03*
X972834Y171260D03*
X968897Y175197D03*
Y167323D03*
X964960Y171260D03*
X961023Y175197D03*
Y167323D03*
X953149Y175197D03*
X957086Y171260D03*
X949212Y194881D03*
X968897Y198818D03*
X964960Y202755D03*
X957086Y210629D03*
X961023Y206692D03*
X972834Y194881D03*
X949212Y210629D03*
X953149Y206692D03*
X964960Y194881D03*
X961023Y198818D03*
X957086Y202755D03*
X949212D03*
X953149Y198818D03*
X957086Y194881D03*
X972834Y210629D03*
Y202755D03*
X968897Y206692D03*
X964960Y210629D03*
X953149Y179134D03*
X961023D03*
X957086Y183071D03*
X953149Y190944D03*
X968897D03*
X972834Y183071D03*
X961023Y190944D03*
X964960Y183071D03*
X968897Y179134D03*
X953149Y210629D03*
X964960Y198818D03*
X961023Y202755D03*
X957086Y206692D03*
X968897Y194881D03*
X953149D03*
X949212Y198818D03*
Y206692D03*
X953149Y202755D03*
X961023Y194881D03*
X957086Y198818D03*
X972834Y206692D03*
X968897Y210629D03*
X972834Y198818D03*
X968897Y202755D03*
X964960Y206692D03*
X961023Y210629D03*
X972834Y190944D03*
X964960Y179134D03*
X961023Y183071D03*
X957086Y190944D03*
X953149Y183071D03*
X957086Y179134D03*
X964960Y190944D03*
X968897Y183071D03*
X972834Y179134D03*
X980708Y175197D03*
X976771Y171260D03*
X980708Y167323D03*
Y171260D03*
X976771Y167323D03*
Y175197D03*
Y179134D03*
Y206692D03*
Y198818D03*
Y190944D03*
X980708Y198818D03*
Y194881D03*
Y202755D03*
Y206692D03*
Y210629D03*
Y190944D03*
Y179134D03*
X976771Y202755D03*
Y210629D03*
Y194881D03*
Y183071D03*
X957086Y155512D03*
X961023D03*
Y151575D03*
X964960Y155512D03*
Y151575D03*
G54D31*
X31977Y126614D03*
Y116614D03*
X91189Y126614D03*
Y116614D03*
Y136614D03*
G54D33*
X143547Y477976D03*
G54D26*
X16200Y120100D03*
X1384200Y122800D03*
X1373200Y823500D03*
G54D29*
X336417Y21260D03*
G54D27*
X42587Y151614D03*
X80579D03*
G54D28*
X293110Y55906D03*
G54D36*
X1333661Y55905D03*
X1376968Y21259D03*
Y90551D03*
G54D30*
X336417D03*
%LPD*%
G75*
G54D10*
G01X20713Y410087D02*
Y418326D01*
G01X17500Y412374D02*
Y706300D01*
G01X42130Y694440D02*
Y692570D01*
X52600Y682100D01*
X60700D01*
G01X127746Y-260199D02*
X95746D01*
G01X117700Y323400D02*
X109400Y331700D01*
Y336595D01*
X86904Y359091D01*
Y385798D01*
G01X127746Y-276199D02*
Y-356199D01*
G01D02*
X1310146D01*
G01X127746Y-311699D02*
X1310146D01*
G01X123746Y-260199D02*
G02I-12000J0D01*
G01X118596D02*
G02I-6850J0D01*
G01X111746Y-276199D02*
Y-244199D01*
G01X127746Y-276199D02*
X1310146D01*
G01X108631Y168836D02*
X157836D01*
X162500Y173500D01*
G01X117700Y323400D02*
X122450Y318650D01*
X142949D01*
X162117Y299482D01*
X162126D01*
X162127Y299481D01*
X163989D01*
X163990Y299482D01*
X168777D01*
X170300Y297959D01*
Y284100D01*
X155662Y269462D01*
Y266438D01*
G01X110042Y544067D02*
Y531546D01*
X116118Y525470D01*
X132072D01*
X133421Y524121D01*
G01X114400Y550000D02*
Y585800D01*
X107100Y593100D01*
Y610187D01*
X105851Y611436D01*
G01X159662Y266600D02*
X162910Y263352D01*
Y244290D01*
G01X155662Y266438D02*
X155824Y266600D01*
X159662D01*
G01X133421Y524121D02*
Y524019D01*
X134270Y523170D01*
G01X219300Y508700D02*
X219200Y508800D01*
X217200D01*
X215200Y510800D01*
Y514785D01*
X216873Y516458D01*
G01X229200Y514800D02*
X229000Y515000D01*
Y530200D01*
X238303Y539503D01*
Y574595D01*
X227500Y585398D01*
Y603500D01*
G01X261100Y521250D02*
Y510775D01*
X263425Y508450D01*
Y508400D01*
X264069Y507756D01*
Y506215D01*
X269789Y500495D01*
Y462834D01*
X273900Y458723D01*
Y313823D01*
X277300Y310423D01*
Y304800D01*
G01X287800Y311600D02*
X279650Y319750D01*
Y505660D01*
X273900Y511410D01*
Y519377D01*
X256177Y537100D01*
X250100D01*
G01X263300Y526300D02*
X265139Y524461D01*
Y524348D01*
X271300Y518187D01*
Y515595D01*
X271299Y515594D01*
Y510334D01*
X271300Y510333D01*
Y506340D01*
X272686Y504954D01*
Y493892D01*
X277000Y489578D01*
Y472078D01*
X273300Y468378D01*
Y463000D01*
X276850Y459450D01*
Y314550D01*
X282700Y308700D01*
Y300100D01*
G01X263300Y526300D02*
X259700Y529900D01*
X251619D01*
X247419Y534100D01*
Y575251D01*
X235220Y587450D01*
Y655220D01*
X236000Y656000D01*
G01X269500Y736150D02*
X267500Y738150D01*
Y748500D01*
X263181Y752819D01*
Y772181D01*
G01X509143Y284391D02*
X508297Y285237D01*
X501724D01*
X496747Y290214D01*
X453542D01*
X443128Y279800D01*
X309599D01*
X287800Y301599D01*
Y311600D01*
G01X297090Y311350D02*
Y310110D01*
X309400Y297800D01*
Y293950D01*
X312900Y290450D01*
G01X331800Y309100D02*
X340000Y317300D01*
X357700D01*
X380900Y340500D01*
X464086D01*
G01X326041Y325000D02*
X326356Y325315D01*
X352593D01*
X353925Y326647D01*
X359132D01*
G01X464086Y287614D02*
X467473Y284227D01*
X483756D01*
X490005Y277978D01*
X511155D01*
X521700Y267433D01*
Y240477D01*
X527751Y234426D01*
Y228302D01*
X535863Y220190D01*
X538308D01*
X541632Y216866D01*
X545638D01*
X546494Y216010D01*
G01X480532Y321332D02*
X476854D01*
X468728Y329458D01*
Y339420D01*
X493700Y364392D01*
Y369300D01*
G01X455450Y376050D02*
X458600Y372900D01*
X490100D01*
X493700Y369300D01*
G01X455450Y376050D02*
Y380050D01*
X459450Y384050D01*
G01X469700Y393300D02*
X469565Y393435D01*
X466735D01*
X459450Y386150D01*
Y384050D01*
G01X496782Y134315D02*
X507700D01*
X507861Y134154D01*
G01X469700Y393300D02*
X487000D01*
G01X522646Y-276199D02*
Y-356199D01*
G01X507861Y134154D02*
X508625Y133390D01*
X555112D01*
X562603Y140881D01*
G01X608089Y131519D02*
X571965D01*
X562603Y140881D01*
G01X569500Y240225D02*
X568203D01*
X553563Y254865D01*
Y306108D01*
G01X660146Y-276199D02*
Y-356199D01*
G01X775146Y-276199D02*
Y-356199D01*
G01X942646Y-276199D02*
Y-356199D01*
G01X1112646Y-276199D02*
Y-356199D01*
G01X1116671Y-3517D02*
Y-315D01*
G01D02*
Y2887D01*
G01X1113469Y-315D02*
X1116671D01*
G01D02*
X1119873D01*
G01X1138324Y30968D02*
Y37520D01*
G01X1131772D02*
X1138324D01*
G01D02*
X1144876D01*
G01X1159978Y-3517D02*
Y-315D01*
G01D02*
Y2887D01*
G01X1156776Y-315D02*
X1159978D01*
G01D02*
X1163180D01*
G01X1175079Y37520D02*
X1181631D01*
G01X1203285Y-3517D02*
Y-315D01*
G01D02*
Y2887D01*
G01X1200083Y-315D02*
X1203285D01*
G01D02*
X1206487D01*
G01X1181631Y30968D02*
Y37520D01*
G01D02*
X1188183D01*
G01X1243390Y-315D02*
X1246592D01*
G01X1224939Y30968D02*
Y37520D01*
G01X1218387D02*
X1224939D01*
G01D02*
X1231491D01*
G01X1246592Y-3517D02*
Y-315D01*
G01D02*
Y2887D01*
G01Y-315D02*
X1249794D01*
G01X1268246Y30968D02*
Y37520D01*
G01X1261694D02*
X1268246D01*
G01D02*
X1274798D01*
G01X1310146Y-276199D02*
Y-356199D01*
G01X1342146Y-260199D02*
X1310146D01*
G01X1289899Y-3517D02*
Y-315D01*
G01D02*
Y2887D01*
G01X1286697Y-315D02*
X1289899D01*
G01D02*
X1293101D01*
G01X1338146Y-260199D02*
G02I-12000J0D01*
G01X1332996D02*
G02I-6850J0D01*
G01X1326146Y-276199D02*
Y-244199D01*
X18577Y107902D03*
X5500Y119571D03*
Y139571D03*
Y159571D03*
X22000Y167200D03*
X5500Y179571D03*
Y199571D03*
X26500Y199500D03*
X21900Y199700D03*
X21800Y188100D03*
X5500Y219571D03*
Y239571D03*
Y259571D03*
X26600Y249217D03*
Y253582D03*
X5500Y279571D03*
Y299571D03*
Y339571D03*
Y319571D03*
Y359571D03*
Y399571D03*
Y379571D03*
X25350Y389000D03*
X17500Y412374D03*
X20713Y410087D03*
X5500Y419571D03*
Y439571D03*
X20713Y418326D03*
X5500Y479571D03*
Y459571D03*
X23720Y472640D03*
X5500Y499571D03*
Y519571D03*
Y539571D03*
X24800Y540900D03*
X5500Y579571D03*
Y559571D03*
Y599571D03*
Y639571D03*
Y619571D03*
Y679571D03*
Y659571D03*
X26100Y671200D03*
X24000Y659000D03*
X29500Y676500D03*
X5500Y699571D03*
X25200Y712650D03*
X17500Y706300D03*
X21300Y728400D03*
X21108Y732713D03*
X5500Y719571D03*
Y739571D03*
Y779571D03*
Y759571D03*
Y799571D03*
X10020Y835051D03*
X30020D03*
X5500Y819571D03*
X63250Y205050D03*
X42800Y200100D03*
X41250Y216728D03*
X53400Y211928D03*
X38050Y216728D03*
X56600Y211928D03*
X63700Y260725D03*
X55800Y266293D03*
X63700Y263925D03*
X55800Y269493D03*
X35300Y303100D03*
X39000Y299500D03*
X53100Y279500D03*
X47800Y309400D03*
X58700Y308600D03*
X62200Y288256D03*
X52050Y316100D03*
X38518Y376916D03*
X34153D03*
X52521Y350357D03*
X54200Y347400D03*
X63500Y353960D03*
X62838Y392392D03*
X47734Y465792D03*
X45531Y474400D03*
X64820Y455887D03*
X64680Y452389D03*
X64500Y459400D03*
X49812Y479921D03*
X33900Y469300D03*
X46500Y460300D03*
X46087Y455819D03*
X61870Y515670D03*
X60300Y533900D03*
X55950Y564500D03*
X53000Y645000D03*
X43600Y665700D03*
X54200Y666800D03*
X60700Y682100D03*
X35766Y673178D03*
X34500Y666500D03*
X39900Y678100D03*
X33600Y675800D03*
X43100Y670900D03*
X36624Y669155D03*
X45800Y685100D03*
X42100Y684000D03*
X59100Y705600D03*
X42130Y694440D03*
X38000Y684000D03*
X50020Y835051D03*
X96584Y195100D03*
X78050Y196300D03*
X77400Y216528D03*
X88800Y210851D03*
X74200Y216528D03*
X92000Y210851D03*
X97480Y266420D03*
X73125Y288231D03*
X76325D03*
X65400Y288256D03*
X83500Y344200D03*
X80300D03*
X77421Y322470D03*
X74221D03*
X82500Y362890D03*
X86904Y385798D03*
X72708Y382055D03*
X89500Y466600D03*
X73900Y527050D03*
X65381Y548719D03*
X87608Y557685D03*
X74500Y713400D03*
X95400Y731600D03*
Y728200D03*
X85800Y727500D03*
Y731000D03*
X93100Y813200D03*
X70020Y835051D03*
X90020D03*
X93300Y818900D03*
X118577Y107902D03*
X104000Y128330D03*
X114364Y122054D03*
X100900Y173800D03*
X108631Y168836D03*
X111967Y199632D03*
X119800Y234531D03*
X103100Y211600D03*
X107340Y266140D03*
X101463Y268811D03*
X117700Y323400D03*
X122000Y343300D03*
X100277Y336077D03*
X102000Y364700D03*
X117300Y361700D03*
X126122Y432323D03*
X131304Y418855D03*
X131004Y422710D03*
X120200Y436400D03*
X127820Y452280D03*
X114400Y550000D03*
X105851Y611436D03*
X111300Y756000D03*
X138577Y107902D03*
X158577D03*
X162500Y173500D03*
X155662Y266438D03*
X159662Y266600D03*
X162910Y244290D03*
X137862Y361723D03*
X161311Y371428D03*
X141216Y361163D03*
X145027D03*
X156573Y371799D03*
X162100Y677800D03*
X164400Y668300D03*
X164500Y693500D03*
X144400Y731600D03*
Y728200D03*
X163800Y771000D03*
X160400D03*
X178577Y107902D03*
X181738Y122711D03*
X183400Y221600D03*
X167600Y247600D03*
X193303Y264310D03*
X167700Y296882D03*
Y292517D03*
X174943Y321015D03*
X192150Y406429D03*
X197000Y404000D03*
X171434Y398093D03*
X185000Y419900D03*
X197531Y451187D03*
X189381Y451394D03*
X193718D03*
X196239Y462262D03*
X177500Y454300D03*
X184189Y564504D03*
X185500Y567700D03*
X193001Y574708D03*
X171300Y678300D03*
X175200Y678500D03*
X199900Y692000D03*
X171000Y715900D03*
X167600D03*
X189000Y684500D03*
X185000D03*
X167000Y686500D03*
X199900Y747500D03*
X194120Y830301D03*
X190920D03*
X227669Y5500D03*
X210028Y12605D03*
Y32605D03*
Y52605D03*
Y72605D03*
X226533Y72591D03*
X228121Y63589D03*
X210028Y92605D03*
X227989Y83589D03*
X233500Y137000D03*
X220300Y129300D03*
X228708Y127115D03*
X215136Y142786D03*
X218299Y123319D03*
X224576Y116678D03*
X221418Y109634D03*
X206200Y247500D03*
X209200Y252800D03*
X230400Y283400D03*
X222200Y300500D03*
X228100Y364600D03*
X219018Y378000D03*
X223383D03*
X217000Y360000D03*
X219580Y356970D03*
X214776Y352807D03*
X212536Y349805D03*
X205915Y422424D03*
X217190Y428485D03*
X212200Y428800D03*
X212000Y438713D03*
X217500Y441992D03*
X200100Y415100D03*
X201868Y451187D03*
X227700Y476537D03*
Y472200D03*
X216404Y469751D03*
X216282Y463288D03*
X228900Y446800D03*
X219300Y508700D03*
X228298Y488100D03*
X228347Y484700D03*
X216873Y516458D03*
X229200Y514800D03*
X203300Y544500D03*
X206700Y554500D03*
X203304Y554684D03*
X205700Y559763D03*
X227500Y603500D03*
X201000Y674000D03*
X206952Y655370D03*
X203300Y692000D03*
X219000Y694000D03*
X231500Y699000D03*
X203300Y747500D03*
X228550Y772700D03*
X231750D03*
X231915Y830301D03*
X219317D03*
X206718D03*
X228715D03*
X216117D03*
X203518D03*
X247669Y5500D03*
X258159Y73589D03*
X257851Y63589D03*
X257769Y83589D03*
X258068Y110180D03*
X259331Y118580D03*
X264443Y109587D03*
X266500Y239400D03*
X245400Y296500D03*
X267300Y362200D03*
X244000Y377617D03*
Y381982D03*
X258500Y391200D03*
X239100Y399200D03*
X251700Y421600D03*
Y425200D03*
X238400Y416200D03*
X264100Y425400D03*
X249342Y439064D03*
X246300Y485400D03*
X246407Y488799D03*
X256300Y494500D03*
X261100Y521250D03*
X250100Y537100D03*
X263300Y526300D03*
X234777Y550569D03*
X266100Y614400D03*
X265850Y606400D03*
X260100Y647400D03*
X259300Y632400D03*
Y639300D03*
X250500Y642500D03*
X265900Y622400D03*
X247717Y633233D03*
X259300Y635900D03*
X236000Y656000D03*
X256600Y652200D03*
X241000Y712500D03*
Y721500D03*
Y725500D03*
Y718000D03*
X263181Y772181D03*
X266561Y830301D03*
X253962D03*
X263361D03*
X250762D03*
X267669Y5500D03*
X271231Y237031D03*
X283622Y226340D03*
X279257D03*
X277300Y304800D03*
X297090Y311350D03*
X282700Y300100D03*
X299600Y297662D03*
X287200Y326802D03*
X287800Y311600D03*
X267979Y342500D03*
X295400Y325390D03*
X283700Y322100D03*
X288270Y365240D03*
X294009Y363063D03*
X282400Y487300D03*
X296200Y566900D03*
X300835Y578165D03*
X279994Y554794D03*
X283600Y551400D03*
X280200D03*
X300835Y583165D03*
X301000Y588665D03*
X288835Y593165D03*
X276300Y617350D03*
X281700Y634900D03*
X281100Y651700D03*
X290338Y715800D03*
X269500Y736150D03*
X286406Y716531D03*
X282406Y716598D03*
X279159Y830301D03*
X275959D03*
X302500Y251600D03*
X311882Y310550D03*
X306800Y290500D03*
X303517Y309777D03*
X312900Y290450D03*
X331800Y309100D03*
X326041Y325000D03*
X315900Y320900D03*
X301320Y362500D03*
X302140Y444160D03*
X306612Y460177D03*
X307400Y467600D03*
X303440Y475360D03*
X303500Y491000D03*
X320500Y531000D03*
X321000Y527000D03*
X322700Y536500D03*
X311406Y535944D03*
X322100Y638500D03*
X307278Y726198D03*
X329553Y830301D03*
X316954D03*
X326353D03*
X313754D03*
X345820Y256570D03*
X349970Y256720D03*
X341652Y305034D03*
Y301534D03*
X359132Y326647D03*
X359500Y448800D03*
X342300Y511600D03*
X350000Y537600D03*
X347100Y605300D03*
X357600Y638300D03*
X364354Y731801D03*
X362091Y729538D03*
X367348Y830301D03*
X354750D03*
X342151D03*
X364148D03*
X351550D03*
X338951D03*
X387669Y5500D03*
X401300Y156715D03*
Y153215D03*
X400400Y189100D03*
X376600Y261350D03*
X381700Y265800D03*
X395100Y449100D03*
X380300Y508700D03*
X401000Y575500D03*
X372000Y579300D03*
X388900Y550400D03*
X386500Y607900D03*
X401994Y830301D03*
X389396D03*
X398794D03*
X386196D03*
X407669Y5500D03*
X427669D03*
X403600Y142542D03*
X433000Y169700D03*
X435161Y166892D03*
X403600Y146042D03*
X422876Y199830D03*
Y204195D03*
X421757Y177999D03*
X411400Y183900D03*
X416100Y470800D03*
X418900Y529300D03*
X410300Y637500D03*
X427191Y830301D03*
X414593D03*
X423991D03*
X411393D03*
X447669Y5500D03*
X467669D03*
X465127Y57727D03*
X438561Y166892D03*
X456500Y169783D03*
Y165418D03*
X464086Y287614D03*
Y340500D03*
X455450Y376050D03*
X469700Y393300D03*
X459450Y384050D03*
X448200Y531400D03*
X443000Y596500D03*
X456335Y835051D03*
X444500Y864450D03*
X489261Y-14185D03*
X496782Y134315D03*
X477037Y333841D03*
X473637Y333876D03*
X480532Y321332D03*
X493700Y369300D03*
X487000Y393300D03*
X472600Y477700D03*
X487400Y492100D03*
X500800Y567200D03*
X496335Y835051D03*
X507861Y134154D03*
X519300Y138871D03*
X530177Y140708D03*
X516100Y138871D03*
X526977Y140708D03*
X529176Y151713D03*
X532560Y152046D03*
X535960Y151999D03*
X507300Y175500D03*
X509143Y284391D03*
X518100Y453200D03*
X520500Y519400D03*
X527941Y864680D03*
X562603Y140881D03*
X544800Y137769D03*
X541600D03*
X549100Y126900D03*
X564483Y167935D03*
X558121Y167249D03*
X548700Y152200D03*
X545500D03*
X569500Y240225D03*
X546494Y216010D03*
X541637Y263240D03*
X545974D03*
X560531Y358080D03*
X564100Y358100D03*
X556500Y358000D03*
X561781Y346281D03*
X561300Y369500D03*
X550000Y381000D03*
X561050Y830301D03*
X548451D03*
X570448D03*
X557850D03*
X545251D03*
X577650Y137780D03*
X587850Y137800D03*
X604450Y137780D03*
X574450D03*
X584650Y137800D03*
X601250Y137780D03*
X597350Y149950D03*
X594150D03*
X596253Y210000D03*
X576100Y234500D03*
X604170Y337900D03*
X599100Y348700D03*
X597500Y352050D03*
X589500Y361000D03*
X581700Y360700D03*
X573900Y360600D03*
X603500Y371200D03*
X576800Y369200D03*
X584500Y462500D03*
X598845Y830301D03*
X586246D03*
X573648D03*
X595645D03*
X583046D03*
X614721Y138287D03*
X608089Y131519D03*
X627826Y137880D03*
X638150D03*
X624626D03*
X634950D03*
X617000Y144500D03*
X636950Y149650D03*
X635482Y207733D03*
X616970Y235017D03*
X624101Y330010D03*
X627500Y329900D03*
X606322Y351522D03*
X633000Y356600D03*
Y360500D03*
Y353000D03*
X636500Y356500D03*
X629500D03*
Y371000D03*
X626458Y372521D03*
X616706Y349718D03*
X618680Y346780D03*
X621300Y366900D03*
X609500Y360717D03*
X623000Y382500D03*
X617000D03*
X636640Y830301D03*
X624042D03*
X611443D03*
X633440D03*
X620842D03*
X608243D03*
X640150Y149650D03*
X649400Y234500D03*
X639500Y342500D03*
X643750Y321500D03*
X640550D03*
X646884Y355616D03*
X639500Y371000D03*
X660244Y352200D03*
Y349000D03*
X653000Y380500D03*
X671285Y830301D03*
X658687D03*
X668085D03*
X655487D03*
X680100Y378718D03*
X683600D03*
X696482Y830301D03*
X683884D03*
X693282D03*
X680684D03*
X729000Y24800D03*
X725314Y24751D03*
X721890Y24887D03*
X719008Y21999D03*
X732500Y98421D03*
X720800Y102150D03*
Y93150D03*
Y78150D03*
X732500Y101621D03*
X720800Y105350D03*
Y96350D03*
Y81350D03*
Y114150D03*
Y117350D03*
X713000Y310000D03*
X727978Y830301D03*
X737377D03*
X724778D03*
X759600Y79200D03*
X768777Y171450D03*
X761242Y169242D03*
X765579D03*
X766950Y189252D03*
X763562Y189539D03*
X770385Y189165D03*
X765774Y830301D03*
X753175D03*
X740577D03*
X762574D03*
X749975D03*
X775381Y66115D03*
X778800Y66388D03*
X782551Y67144D03*
X786333Y66963D03*
X806665Y174050D03*
X803265D03*
X773984Y189118D03*
X803569Y830301D03*
X790970D03*
X778372D03*
X800369D03*
X787770D03*
X775172D03*
X838252Y20800D03*
X834500D03*
X830500D03*
X828283Y24734D03*
X824462Y25770D03*
X808114Y67634D03*
X823551Y80551D03*
X816167Y830301D03*
X838164D03*
X812967D03*
X849051Y20908D03*
X845052Y20800D03*
X841652D03*
X848623Y70757D03*
X852019Y70589D03*
X855421Y70551D03*
X858821Y70614D03*
X868800Y85300D03*
X864800Y707700D03*
X868200D03*
X861406Y804403D03*
X857406D03*
X853962Y830301D03*
X841364D03*
X850762D03*
X861823Y853696D03*
X905488Y54479D03*
X884412Y835051D03*
X915486Y41030D03*
X918952Y40680D03*
X909797Y55037D03*
X929800Y105900D03*
X938898Y640169D03*
X916319Y678588D03*
Y658588D03*
Y698588D03*
Y738588D03*
Y718588D03*
Y778588D03*
Y758588D03*
Y798588D03*
Y818588D03*
X949102Y74964D03*
X959300Y68600D03*
Y72000D03*
X964105Y62308D03*
X959855Y61107D03*
X949893Y106378D03*
X949828Y109778D03*
X957800Y570300D03*
X958898Y640169D03*
X985579Y26494D03*
X985403Y22993D03*
X994650Y39880D03*
X997007Y49560D03*
X1008508Y47704D03*
X1006100Y528700D03*
X977500Y550000D03*
X978898Y640169D03*
X994248Y665818D03*
Y685818D03*
Y705818D03*
Y745818D03*
Y725818D03*
Y765818D03*
Y805818D03*
Y785818D03*
X1033017Y14743D03*
X1033554Y30216D03*
X1040241Y61043D03*
X1036854Y47110D03*
X1022600Y542100D03*
X1017800Y572700D03*
X1043300Y631300D03*
X1041500Y682000D03*
X1041900Y658100D03*
X1041314Y830301D03*
X1024004Y855893D03*
X1062044Y-4173D03*
X1065620Y-4335D03*
X1072800Y-800D03*
X1069261Y-14185D03*
X1049261D03*
X1060800Y10100D03*
X1044050Y28815D03*
X1047500Y41500D03*
X1051000D03*
X1049772Y57259D03*
X1049470Y53749D03*
X1057000Y54500D03*
X1071135Y60375D03*
X1057000Y57700D03*
X1071135Y57175D03*
X1047000Y644000D03*
X1045000Y617500D03*
X1069711Y830301D03*
X1057112D03*
X1044514D03*
X1066511D03*
X1053912D03*
X1084000Y500D03*
X1089261Y-14185D03*
X1083315Y36654D03*
X1082808Y30601D03*
X1092094Y30362D03*
X1080672Y9500D03*
X1084800Y9400D03*
X1083379Y40889D03*
X1083500Y25500D03*
X1105441Y54768D03*
X1100992Y52374D03*
X1078694Y43478D03*
X1088287Y55917D03*
X1096496Y51226D03*
X1107506Y830301D03*
X1094907D03*
X1082309D03*
X1104306D03*
X1091707D03*
X1079109D03*
X1122001Y133324D03*
X1141900Y137851D03*
X1122001Y130124D03*
X1138700Y137851D03*
X1132703Y830301D03*
X1120104D03*
X1142101D03*
X1129503D03*
X1116904D03*
X1161307Y138505D03*
X1158107D03*
X1157899Y830301D03*
X1145301D03*
X1176747D03*
X1154699D03*
X1182061Y142478D03*
X1190835Y137899D03*
X1199400Y142851D03*
X1178861Y142478D03*
X1187635Y137899D03*
X1196200Y142851D03*
X1206991Y156730D03*
X1203791D03*
X1205500Y334400D03*
X1192545Y830301D03*
X1179947D03*
X1189345D03*
X1234209Y142463D03*
X1242900Y137851D03*
X1225348Y137960D03*
X1231009Y142463D03*
X1239700Y137851D03*
X1222148Y137960D03*
X1226000Y261300D03*
X1242000Y343000D03*
X1235400Y364400D03*
X1213400Y355400D03*
X1214100Y469800D03*
X1237800Y524500D03*
X1232300Y568900D03*
X1236640Y830301D03*
X1224042D03*
X1233440D03*
X1220842D03*
X1277265Y137673D03*
X1274065D03*
X1261944Y145770D03*
X1258744D03*
X1251801Y144871D03*
X1258500Y335500D03*
X1266500D03*
X1270500D03*
X1273500Y397000D03*
X1257500D03*
X1254000D03*
X1259200Y471800D03*
X1259000Y680000D03*
X1265000Y672000D03*
X1253500D03*
X1278000Y689000D03*
X1274435Y830301D03*
X1261837D03*
X1249239D03*
X1271235D03*
X1258637D03*
X1246039D03*
X1286543Y141581D03*
X1296017Y137478D03*
X1283343Y141581D03*
X1292817Y137478D03*
X1312200Y275200D03*
X1309900Y292400D03*
X1297500Y351800D03*
X1311500Y391000D03*
X1310068Y394084D03*
X1291600Y495200D03*
X1296400Y542400D03*
X1294700Y593400D03*
X1302128Y674067D03*
X1306128Y674000D03*
X1297400Y651300D03*
X1290550D03*
X1285000Y694000D03*
X1280500Y706000D03*
X1310376Y687205D03*
X1301728Y711200D03*
X1310100Y732900D03*
X1294628Y733000D03*
X1306128Y732872D03*
X1302128D03*
X1312231Y830301D03*
X1287033D03*
X1309031D03*
X1283833D03*
X1324845Y130527D03*
X1331243Y182198D03*
X1345850Y676750D03*
X1333500Y709500D03*
X1323076Y686999D03*
X1338200Y689800D03*
X1315546Y709500D03*
X1341400Y686900D03*
X1326661Y740700D03*
X1337427Y830301D03*
X1324829D03*
X1346825D03*
X1334227D03*
X1321629D03*
X1355321Y172119D03*
X1369700Y424600D03*
X1366000Y472900D03*
X1363900Y537600D03*
X1361800Y596800D03*
X1358700Y655700D03*
X1348500Y713000D03*
X1377000Y725000D03*
X1378000Y806900D03*
X1369925Y835051D03*
X1350025Y830301D03*
X1394500Y139626D03*
Y119626D03*
Y159626D03*
X1381696Y173459D03*
X1394500Y199626D03*
Y179626D03*
X1382138Y184129D03*
X1394500Y239626D03*
Y219626D03*
Y259626D03*
Y299626D03*
Y279626D03*
Y339626D03*
Y319626D03*
Y359626D03*
Y399626D03*
Y379626D03*
Y439626D03*
Y419626D03*
Y479626D03*
Y459626D03*
Y499626D03*
Y539626D03*
Y519626D03*
Y579626D03*
Y559626D03*
Y599626D03*
Y639626D03*
Y619626D03*
Y679626D03*
Y659626D03*
Y699626D03*
Y739626D03*
Y719626D03*
Y759626D03*
Y779626D03*
Y799626D03*
Y819626D03*
X1389925Y835051D03*
G54D20*
G01X55950Y564500D02*
X56100Y564350D01*
X56850Y565100D01*
X81390D01*
X83055Y563435D01*
X86161D01*
X86210Y563386D01*
X86532D01*
X86581Y563435D01*
X88529D01*
X88539Y563425D01*
X90021D01*
X92669Y560777D01*
Y559551D01*
X96900Y555320D01*
X102980D01*
X111034Y547266D01*
G01D02*
X127624D01*
X130023Y544867D01*
Y541217D01*
X130022Y541216D01*
Y540967D01*
X127973Y538918D01*
G01X111034Y547266D02*
X110042Y546274D01*
Y544067D01*
G54D11*
X122700Y476100D03*
Y478400D03*
X122600Y473800D03*
Y471500D03*
X121673Y497973D03*
Y494822D03*
X127973Y488524D03*
X131122D03*
Y485374D03*
X121673Y504272D03*
X127973Y491674D03*
Y538918D03*
X131369Y617244D03*
X140569Y494823D03*
X134270Y510571D03*
X134272Y491674D03*
X153188Y538899D03*
X162617Y535766D03*
X146869Y538954D03*
X146858Y535742D03*
X159449Y542048D03*
Y538898D03*
X159456Y532642D03*
X162617Y542066D03*
Y538916D03*
X149981Y538917D03*
X153132Y535767D03*
X149985Y535771D03*
X153194Y542078D03*
X153187Y532636D03*
X146869Y529469D03*
X134270Y523170D03*
X159537Y548256D03*
X147451Y556436D03*
X142951Y555636D03*
X160700Y551356D03*
X151989Y557138D03*
X161280Y556100D03*
X151989Y554838D03*
X161280Y558400D03*
X137661Y614096D03*
X150269Y598347D03*
X156566Y614095D03*
X143968Y601495D03*
X140821Y614106D03*
X166016Y601496D03*
X159716Y610945D03*
Y614095D03*
Y595197D03*
X166016Y610944D03*
X162867Y614095D03*
X147115Y598360D03*
X150268Y601496D03*
X147141Y614096D03*
X143968Y588898D03*
X153417Y610945D03*
X159716Y604645D03*
X166015Y598345D03*
X147117Y610945D03*
X162865Y601495D03*
X150268Y610944D03*
X159716Y601495D03*
X150251Y617226D03*
X168916Y510571D03*
Y523170D03*
X175215Y532618D03*
X178365Y535768D03*
X172065Y532618D03*
X874410Y139764D03*
Y131890D03*
Y120079D03*
Y124016D03*
Y155512D03*
Y147638D03*
Y206692D03*
Y194881D03*
Y183071D03*
Y230314D03*
Y222440D03*
Y214566D03*
X878347Y135827D03*
Y116142D03*
X882284Y120079D03*
X886221Y116142D03*
X890158Y120079D03*
X894095Y116142D03*
X898032Y120079D03*
X901969Y116142D03*
X878347Y139764D03*
X882284Y135827D03*
X878347Y131890D03*
Y120079D03*
X882300Y124032D03*
X886221Y120079D03*
X890158Y124016D03*
X894095Y120079D03*
X898032Y124016D03*
X901969Y120079D03*
X905906Y139764D03*
Y135827D03*
Y131890D03*
X878347Y159449D03*
Y151575D03*
Y143701D03*
X882284Y159449D03*
X878347Y155512D03*
X882284Y151575D03*
X878347Y147638D03*
X882284Y143701D03*
X905906Y155512D03*
Y147638D03*
Y143701D03*
X878347Y198818D03*
Y190944D03*
Y206692D03*
X882284Y198818D03*
X878347Y194881D03*
X882284Y190944D03*
X878347Y183071D03*
Y234251D03*
Y226377D03*
Y218503D03*
Y210629D03*
X882284Y234251D03*
X878347Y230314D03*
X882284Y226377D03*
X878347Y222440D03*
X882284Y218503D03*
X878347Y214566D03*
X882284Y210629D03*
X905906Y257873D03*
X901969Y261810D03*
X898032Y257873D03*
X894095Y261810D03*
X890158Y257873D03*
X886221Y261810D03*
X882284Y257873D03*
X878347Y261810D03*
X905906Y253936D03*
X901969Y257873D03*
X898032Y253936D03*
X894095Y257873D03*
X890158Y253936D03*
X886221Y257873D03*
X882284Y253936D03*
X878347Y257873D03*
X909843Y131890D03*
X913780D03*
X937402Y139764D03*
Y127953D03*
X925591Y139764D03*
X941339Y131890D03*
Y135827D03*
X913780Y159449D03*
X937402D03*
X925591Y151575D03*
X913780Y147638D03*
X917717Y159449D03*
X913780Y155512D03*
Y151575D03*
X933465Y155512D03*
X929528D03*
X925591Y143701D03*
Y147638D03*
X909843Y155512D03*
X941339Y143701D03*
Y147638D03*
X913780Y214566D03*
X941339Y257873D03*
X937402Y261810D03*
X933465Y257873D03*
X929528Y261810D03*
X925591Y257873D03*
X921654Y261810D03*
X917717Y257873D03*
X913780Y261810D03*
X941339Y253936D03*
X937402Y257873D03*
X933465Y253936D03*
X929528Y257873D03*
X925591Y253936D03*
X921654Y257873D03*
X917717Y253936D03*
X913780Y257873D03*
X964960Y131890D03*
X961023Y139764D03*
X964960Y135827D03*
Y139764D03*
X953149Y163386D03*
X968897Y151575D03*
X964960Y159449D03*
X957086D03*
X953149Y151575D03*
X949212Y159449D03*
X972834D03*
X957086Y151575D03*
X964960Y143701D03*
X968897Y155512D03*
X972834Y261810D03*
X968897Y257873D03*
X964960Y261810D03*
X961023Y257873D03*
X957086Y261810D03*
X953149Y257873D03*
X972834D03*
X968897Y253936D03*
X964960Y257873D03*
X961023Y253936D03*
X957086Y257873D03*
X953149Y253936D03*
X980708Y127953D03*
Y139764D03*
X992519Y115742D03*
X996456Y120079D03*
X1000393Y116142D03*
X1004330Y120079D03*
X1008267Y116142D03*
X992519Y120079D03*
X996456Y124016D03*
X1000393Y120079D03*
X1004330Y124016D03*
X1008267Y120079D03*
X988582Y139764D03*
Y135827D03*
X984645Y131890D03*
X988582Y147638D03*
Y143701D03*
X984645Y151575D03*
X980708Y183071D03*
Y214566D03*
X1008267Y261810D03*
X1004330Y257873D03*
X1000393Y261810D03*
X996456Y257873D03*
X992519Y261810D03*
X988582Y257873D03*
X980708Y261810D03*
X976771Y257873D03*
X1008267D03*
X1004330Y253936D03*
X1000393Y257873D03*
X996456Y253936D03*
X992519Y257873D03*
X988582Y253936D03*
X980708Y257873D03*
X976771Y253936D03*
X1020078Y139764D03*
X1012204Y120079D03*
X1016141Y116142D03*
X1020078Y120079D03*
Y131890D03*
X1016141Y135827D03*
Y139764D03*
X1012204Y124016D03*
X1016141Y120079D03*
X1023278D03*
X1016141Y131890D03*
X1012204Y135827D03*
X1016141Y143701D03*
X1020078Y147638D03*
X1016141Y151575D03*
X1020078Y155512D03*
X1016141Y159449D03*
X1020078Y167323D03*
X1016141Y171260D03*
X1020078Y175197D03*
X1012204Y143701D03*
X1016141Y147638D03*
X1012204Y151575D03*
X1016141Y155512D03*
X1012204Y159449D03*
X1016141Y167323D03*
X1012204Y171260D03*
X1016141Y175197D03*
Y179134D03*
X1020078Y183071D03*
X1016141Y190944D03*
X1020078Y194881D03*
X1016141Y198818D03*
X1020078Y206692D03*
X1012204Y179134D03*
X1016141Y183071D03*
X1012204Y190944D03*
X1016141Y194881D03*
X1012204Y198818D03*
X1016141Y206692D03*
Y210629D03*
X1020078Y214566D03*
X1016141Y218503D03*
X1020078Y222440D03*
X1016141Y226377D03*
X1020078Y230314D03*
X1016141Y234251D03*
X1012204Y210629D03*
X1016141Y214566D03*
X1012204Y218503D03*
X1016141Y222440D03*
X1012204Y226377D03*
X1016141Y230314D03*
X1012204Y234251D03*
X1016141Y261810D03*
X1012204Y257873D03*
X1016141D03*
X1012204Y253936D03*
G54D21*
G01X41250Y216728D02*
X40250Y217728D01*
Y221650D01*
X32697Y229203D01*
Y235929D01*
X33447Y236679D01*
Y237879D01*
X32697Y238629D01*
Y239829D01*
X33447Y240579D01*
Y241779D01*
X32697Y242529D01*
Y244598D01*
X36029Y247930D01*
X37090D01*
X37939Y248779D01*
Y249840D01*
X38787Y250688D01*
X39848D01*
X40696Y251537D01*
Y252597D01*
X41545Y253446D01*
X42605D01*
X43454Y254294D01*
Y255355D01*
X44302Y256203D01*
X45363D01*
X46212Y257052D01*
Y258113D01*
X48199Y260100D01*
Y271592D01*
X52207Y275600D01*
X53599D01*
X56199Y278200D01*
Y288299D01*
X61800Y293900D01*
X67402D01*
X69702Y291600D01*
X72800D01*
X74125Y290275D01*
Y289231D01*
X73125Y288231D01*
G01X62200Y288256D02*
X63200Y287256D01*
Y280900D01*
X55500Y273200D01*
X53202D01*
X50600Y270598D01*
Y257900D01*
X37000Y244300D01*
Y229200D01*
X46400Y219800D01*
X51870D01*
X54400Y217270D01*
Y212928D01*
X53400Y211928D01*
G01X38050Y216728D02*
X39050Y217728D01*
Y221152D01*
X31497Y228705D01*
Y245096D01*
X46999Y260598D01*
Y272090D01*
X51709Y276800D01*
X53101D01*
X54999Y278698D01*
Y288797D01*
X61302Y295100D01*
X67900D01*
X70200Y292800D01*
X73298D01*
X75325Y290773D01*
Y289231D01*
X76325Y288231D01*
G01X65400Y288256D02*
X64400Y287256D01*
Y280402D01*
X55998Y272000D01*
X53700D01*
X51800Y270100D01*
Y257402D01*
X38200Y243802D01*
Y229698D01*
X46898Y221000D01*
X52368D01*
X55600Y217768D01*
Y212928D01*
X56600Y211928D01*
G01X77400Y216528D02*
X76400Y217528D01*
Y221100D01*
X81900Y226600D01*
Y234800D01*
X59900Y256800D01*
Y260988D01*
X60637Y261725D01*
X62700D01*
X63700Y260725D01*
G01X88800Y210851D02*
X89700Y211751D01*
Y214202D01*
X84300Y219602D01*
Y238402D01*
X74527Y248175D01*
Y262749D01*
X67276Y270000D01*
X61700D01*
X59000Y267300D01*
X56807D01*
X55800Y266293D01*
G01X74200Y216528D02*
X75200Y217528D01*
Y221598D01*
X80700Y227098D01*
Y234302D01*
X58700Y256302D01*
Y261486D01*
X60139Y262925D01*
X62700D01*
X63700Y263925D01*
G01X92000Y210851D02*
X90900Y211951D01*
Y214700D01*
X85500Y220100D01*
Y238900D01*
X75727Y248673D01*
Y263247D01*
X67774Y271200D01*
X61202D01*
X58502Y268500D01*
X56793D01*
X55800Y269493D01*
G01X871437Y181108D02*
G03X872096Y180835I659J659D01*
G01X872946D01*
X875129Y181219D01*
X875915Y181771D01*
X876101Y181957D01*
X876167Y182032D01*
X876172Y182038D01*
X876182Y182045D01*
X876621Y182617D01*
G03X876726Y182954I-408J312D01*
G01Y182958D01*
G03X876402Y183560I-721J0D01*
G03X876016Y183720I-386J-386D01*
G01X875475D01*
G03X875183Y183654I-1J-675D01*
G01X875069Y183599D01*
G03X874619Y183280I710J-1478D01*
G01X874410Y183071D01*
G01X878347D02*
G03X877758Y182781I0J-743D01*
G01X876816Y181557D01*
G02X876678Y181400I-1272J979D01*
G01X876429Y181152D01*
X876428D01*
X875443Y180461D01*
X872022Y179859D01*
X871971Y179808D01*
X871437D01*
G01X872814Y193111D02*
X872912Y193128D01*
X873057Y193026D01*
G03X873377Y192955I245J349D01*
G01X875297Y193294D01*
G03X875973Y193646I-221J1249D01*
G01X876253Y193926D01*
G03X876594Y194749I-823J823D01*
G01Y194778D01*
G03X876240Y195437I-1275J-260D01*
G01X876127Y195484D01*
G03X875896Y195530I-232J-560D01*
G01X875475D01*
G03X875183Y195464I-1J-675D01*
G01X875069Y195409D01*
G03X874619Y195090I710J-1478D01*
G01X874410Y194881D01*
G01X875666Y188983D02*
X875710Y189027D01*
X877362D01*
X879234Y189357D01*
G03X879910Y189709I-221J1249D01*
G01X880089Y189888D01*
G03X880381Y190543I-708J708D01*
G01X880405Y191001D01*
G03X879020Y191618I-811J43D01*
G01X878347Y190945D01*
Y190944D01*
G01X882284Y198818D02*
G03X881695Y198528I0J-743D01*
G01X880753Y197304D01*
G02X880615Y197147I-1272J979D01*
G01X880366Y196899D01*
X880365Y196898D01*
G02X879234Y196431I-1131J1136D01*
G01X876632D01*
G02X874934Y196789I0J4206D01*
G03X873559Y197147I-1791J-4058D01*
G01X873040Y191830D02*
X873312Y192130D01*
X875380Y192496D01*
G03X876428Y192961I-83J1600D01*
G01X876429Y192962D01*
X876678Y193210D01*
X878347Y194879D01*
Y194881D01*
G01X876433Y187797D02*
X876531Y187814D01*
X876733Y188103D01*
X876736Y188104D01*
X876807Y188116D01*
X879317Y188559D01*
G03X880365Y189024I-83J1600D01*
G01X880479Y189138D01*
X880807Y189455D01*
X880852Y189500D01*
G03X880932Y189598I-455J453D01*
G01X880971Y189656D01*
G03X881096Y189892I-1148J759D01*
G01X881143Y190005D01*
G02X881573Y190647I1818J-753D01*
G01X881582Y190656D01*
G02X882276Y190944I694J-692D01*
G01X882284D01*
G01X878347Y198818D02*
X878556Y199027D01*
G02X879006Y199346I1160J-1159D01*
G02X879243Y199429I483J-998D01*
G01X879313Y199445D01*
G02X879455Y199456I109J-483D01*
G01X879569Y199449D01*
G02X879788Y199394I-36J-608D01*
G01X879870Y199356D01*
G02X880162Y199096I-276J-604D01*
G02X880343Y198277I-1762J-819D01*
G02X880119Y197792I-1551J422D01*
G01X879787Y197460D01*
G02X879234Y197231I-553J553D01*
G01X876632D01*
G02X874739Y197806I0J3404D01*
G01X874410Y206692D02*
X874619Y206901D01*
G02X875069Y207220I1160J-1159D01*
G01X875183Y207275D01*
G02X875475Y207341I291J-609D01*
G01X875917D01*
G02X876108Y207303I0J-499D01*
G01X876207Y207262D01*
G02X876598Y206500I-1059J-1025D01*
G02X876331Y205860I-1338J182D01*
G02X876009Y205493I-2970J2281D01*
G01X875850Y205334D01*
G02X875297Y205105I-553J553D01*
G01X872829D01*
G02X872600Y205200I0J324D01*
G01X882284Y210629D02*
G03X881695Y210339I0J-743D01*
G01X881499Y210085D01*
X881476Y210055D01*
X881324Y209857D01*
X881298Y209824D01*
X881214Y209715D01*
X881051Y209503D01*
X880971Y209399D01*
X880753Y209115D01*
G02X880615Y208958I-1272J979D01*
G01X880366Y208710D01*
X880365Y208709D01*
G02X879234Y208242I-1131J1136D01*
G01X873826D01*
G03X873000Y207900I0J-1168D01*
G01X878347Y206692D02*
G03X877758Y206402I0J-743D01*
G01X877562Y206148D01*
X877539Y206118D01*
X877387Y205920D01*
X877366Y205894D01*
X877361Y205887D01*
X877255Y205749D01*
X877114Y205566D01*
X876816Y205178D01*
G02X876678Y205021I-1272J979D01*
G01X876429Y204773D01*
X876428Y204772D01*
G02X875297Y204305I-1131J1136D01*
G01X873578D01*
G03X872600Y203900I0J-1383D01*
G01X878347Y210629D02*
G02X879127Y211322I1236J-605D01*
G02X879583Y211400I457J-1298D01*
G02X879988Y211224I1J-552D01*
G01X880125Y211076D01*
G02X880400Y210412I-759J-703D01*
G02X880171Y209735I-1004J-38D01*
G01X879787Y209271D01*
G02X879234Y209042I-553J553D01*
G01X873381D01*
G02X873000Y209200I0J539D01*
G01X874410Y214566D02*
X874619Y214775D01*
G02X875069Y215094I1160J-1159D01*
G01X875183Y215149D01*
G02X875475Y215215I291J-609D01*
G01X875740D01*
G02X876255Y214960I1J-646D01*
G01X876337Y214852D01*
G02X876375Y213843I-667J-530D01*
G02X875850Y213208I-3611J2451D01*
G02X875297Y212979I-553J553D01*
G01X873696D01*
G02X873226Y213173I-1J664D01*
G01X873200Y213200D01*
G01X878347Y214566D02*
G03X877758Y214276I0J-743D01*
G01X877562Y214022D01*
X877539Y213992D01*
X877387Y213794D01*
X877361Y213761D01*
X877114Y213440D01*
X876816Y213052D01*
G02X876678Y212895I-1272J979D01*
G01X876429Y212647D01*
X876428Y212646D01*
G02X875297Y212179I-1131J1136D01*
G01X873711D01*
G03X873315Y212015I0J-560D01*
G01X873200Y211900D01*
G01X878347Y218503D02*
X878556Y218712D01*
G02X879006Y219031I1160J-1159D01*
G01X879120Y219086D01*
G02X879412Y219152I291J-609D01*
G01X879677D01*
G02X880192Y218897I1J-646D01*
G01X880274Y218789D01*
G02X880312Y217780I-667J-530D01*
G02X879787Y217145I-3611J2451D01*
G02X879234Y216916I-553J553D01*
G01X873786D01*
G02X873100Y217200I0J970D01*
G01Y219800D02*
X873150D01*
X873403Y220053D01*
X875297D01*
G03X876416Y220516I1J1582D01*
G01X878343Y222443D01*
X878344D01*
X878347Y222440D01*
G01X882284Y218503D02*
G03X881695Y218213I0J-743D01*
G01X881499Y217959D01*
X881476Y217929D01*
X881324Y217731D01*
X881298Y217698D01*
X881051Y217377D01*
X880753Y216989D01*
G02X880615Y216832I-1272J979D01*
G01X880366Y216584D01*
X880365Y216583D01*
G02X879234Y216116I-1131J1136D01*
G01X873621D01*
G03X873100Y215900I0J-737D01*
G01Y221100D02*
G03X873696Y220853I596J596D01*
G01X875297D01*
G03X875850Y221082I0J782D01*
G01X876434Y221666D01*
G03X876623Y222122I-456J456D01*
G01Y222190D01*
G03X876599Y222311I-317J0D01*
G03X876331Y222691I-976J-404D01*
G01X876257Y222765D01*
G03X875475Y223089I-782J-782D01*
G03X875183Y223023I-1J-675D01*
G01X875069Y222968D01*
G03X874619Y222649I710J-1478D01*
G01X874410Y222440D01*
G01X945000Y144600D02*
Y144500D01*
X944875Y144375D01*
G03X944750Y144073I302J-302D01*
G01Y134458D01*
G02X943450Y133158I-1300J0D01*
G01X941839D01*
G03X941339Y132658I0J-500D01*
G01Y131890D01*
G01Y135827D02*
Y134458D01*
G03X941839Y133958I500J0D01*
G01X943450D01*
G03X943950Y134458I0J500D01*
G01Y144073D01*
G03X943825Y144375I-427J0D01*
G01X943700Y144500D01*
Y144600D01*
G01X873439Y233806D02*
X873719Y233526D01*
G03X875800Y232664I2081J2081D01*
G01X879234D01*
G03X879787Y232893I0J782D01*
G01X880119Y233225D01*
G03X880312Y233528I-1420J1117D01*
G01X880356Y233657D01*
G03X880321Y234371I-907J313D01*
G01X880212Y234608D01*
G03X879702Y234900I-510J-299D01*
G01X879412D01*
G03X879120Y234834I-1J-675D01*
G01X879006Y234779D01*
G03X878556Y234460I710J-1478D01*
G01X878347Y234251D01*
G01X872600Y229000D02*
G03X873259Y228727I659J659D01*
G01X875297D01*
G03X875850Y228956I0J782D01*
G03X876419Y229720I-2327J2327D01*
G03X876384Y230434I-907J313D01*
G01X876275Y230671D01*
G03X875765Y230963I-510J-299D01*
G01X875475D01*
G03X875183Y230897I-1J-675D01*
G01X875069Y230842D01*
G03X874619Y230523I710J-1478D01*
G01X874410Y230314D01*
G01X873300Y225000D02*
G03X873807Y224790I507J507D01*
G01X879234D01*
G03X879787Y225019I0J782D01*
G03X880312Y225654I-3086J3086D01*
G03X880274Y226663I-705J479D01*
G01X880192Y226771D01*
G03X879677Y227026I-514J-391D01*
G01X879412D01*
G03X879120Y226960I-1J-675D01*
G01X879006Y226905D01*
G03X878556Y226586I710J-1478D01*
G01X878347Y226377D01*
G01X872006Y233585D02*
G03X875500Y231864I3494J2686D01*
G01X879566D01*
G03X880135Y232099I1J804D01*
G01X880615Y232580D01*
G03X880753Y232737I-1134J1136D01*
G01X880754Y232736D01*
G03X881027Y233167I-2056J1604D01*
G01X881243Y233596D01*
X881253Y233616D01*
G02X881337Y233757I1031J-519D01*
G02X882284Y234251I947J-660D01*
G01X872700Y227700D02*
G02X873248Y227927I548J-548D01*
G01X875297D01*
G03X876428Y228394I0J1603D01*
G01X876429Y228395D01*
X876678Y228643D01*
G03X876816Y228800I-1134J1136D01*
G01X877114Y229188D01*
X877257Y229375D01*
X877361Y229509D01*
X877387Y229542D01*
X877539Y229740D01*
X877562Y229770D01*
X877758Y230024D01*
G02X878347Y230314I589J-453D01*
G01X873300Y223700D02*
G02X874000Y223990I700J-700D01*
G01X879234D01*
G03X880365Y224457I0J1603D01*
G01X880366Y224458D01*
X880615Y224706D01*
G03X880753Y224863I-1134J1136D01*
G01X881051Y225251D01*
X881298Y225572D01*
X881324Y225605D01*
X881476Y225803D01*
X881499Y225833D01*
X881695Y226087D01*
G02X882284Y226377I589J-453D01*
G01X877784Y266942D02*
Y266500D01*
X880697Y263587D01*
Y256590D01*
G03X880900Y256100I693J0D01*
G03X881383Y255900I483J483D01*
G01X881761D01*
G03X882142Y256058I0J539D01*
G01X882492Y256408D01*
G03Y257665I-629J628D01*
G01X882284Y257873D01*
G01X876813Y266062D02*
X877090D01*
X879897Y263255D01*
Y256373D01*
G03X880229Y255570I1135J-1D01*
G01X880830Y254968D01*
X881567Y254233D01*
G03X882284Y253936I717J717D01*
G01X890158Y257873D02*
G02X890100Y256500I-1895J-608D01*
G02X889849Y256136I-984J410D01*
G02X889257Y255900I-592J625D01*
G02X888774Y256100I0J683D01*
G02X888571Y256590I490J490D01*
G01Y263525D01*
X888946Y263900D01*
G01X884900Y263700D02*
X884634Y263434D01*
Y260527D01*
G03X884837Y260037I693J0D01*
G03X885320Y259837I483J483D01*
G01X885698D01*
G03X886079Y259995I0J539D01*
G01X886109Y260025D01*
G03X886321Y260537I-512J512D01*
G01Y261710D01*
X886221Y261810D01*
G01X887646Y263900D02*
X887771Y263775D01*
Y256373D01*
G03X888103Y255570I1135J-1D01*
G01X888816Y254857D01*
X889441Y254233D01*
G03X890158Y253936I717J717D01*
G01X886221Y257873D02*
G02X885504Y258170I0J1014D01*
G01X884166Y259507D01*
G02X883834Y260310I803J802D01*
G01Y263466D01*
X883600Y263700D01*
G01X978221Y104782D02*
Y105204D01*
X978821Y105804D01*
Y111672D01*
X978358Y112135D01*
Y117117D01*
X979754Y118513D01*
X981541D01*
X982260Y119232D01*
Y125297D01*
X983095Y126132D01*
Y128596D01*
X984802Y130303D01*
X985251D01*
X986195Y131247D01*
Y137377D01*
X988582Y139764D01*
G01X980221Y105104D02*
Y105204D01*
X979621Y105804D01*
Y112004D01*
X979158Y112467D01*
Y116785D01*
X980086Y117713D01*
X981873D01*
X983060Y118900D01*
Y124965D01*
X983661Y125566D01*
X984451D01*
X987000Y128115D01*
Y134245D01*
X988582Y135827D01*
G01X913780Y147638D02*
X916130Y145288D01*
Y139158D01*
X917074Y138214D01*
X917523D01*
X919267Y136470D01*
Y117981D01*
X918890Y117604D01*
G01X917717Y159449D02*
Y158492D01*
X920104Y156105D01*
Y146995D01*
X920867Y146232D01*
Y142744D01*
X923204Y140407D01*
Y115204D01*
X922500Y114500D01*
G01X916217Y113700D02*
X916167Y113750D01*
Y137989D01*
X915330Y138826D01*
Y144344D01*
X914423Y145251D01*
X913974D01*
X912230Y146995D01*
Y153962D01*
X913780Y155512D01*
G01X919000Y115338D02*
X920067Y116405D01*
Y145900D01*
X919304Y146663D01*
Y148244D01*
X917848Y149700D01*
X916700D01*
X914825Y151575D01*
X913780D01*
G01X912243Y113500D02*
X912230Y113513D01*
Y140399D01*
X911393Y141236D01*
Y157062D01*
X913780Y159449D01*
G01Y131890D02*
X915330Y130340D01*
Y113930D01*
X914900Y113500D01*
G01X874410Y155512D02*
G03X876627Y155826I1056J530D01*
G03X876631Y156420I-1657J308D01*
G03X876075Y157034I-896J-252D01*
G03X875425Y157081I-650J-4471D01*
G01X871730D01*
G03X871428Y156956I0J-427D01*
G01X871303Y156831D01*
X871203D01*
G01X878347Y151575D02*
X879475D01*
G03X879915Y152015I0J440D01*
G01Y152375D01*
G03X879146Y153144I-769J0D01*
G01X872927D01*
G03X872625Y153019I0J-427D01*
G01X872500Y152894D01*
X872400D01*
G01X871203Y158131D02*
X871303D01*
X871553Y157881D01*
X875685D01*
G02X876875Y157572I1J-2442D01*
G02X878347Y155512I-1441J-2586D01*
G01X872400Y154194D02*
X872500D01*
X872750Y153944D01*
X879146D01*
G02X880715Y152375I0J-1569D01*
G01Y151975D01*
G03X881210Y151480I495J0D01*
G01X882189D01*
X882284Y151575D01*
G01X871800Y149050D02*
X871900D01*
X872150Y149300D01*
X874756D01*
G02X875978Y148078I0J-1222D01*
G02X875538Y147638I-440J0D01*
G01X874410D01*
G01X871606Y150350D02*
X871656D01*
X871706Y150300D01*
Y150212D01*
X871818Y150100D01*
X874756D01*
G02X876778Y148078I0J-2022D01*
G01Y148038D01*
G03X877276Y147540I498J0D01*
G01X878249D01*
X878347Y147638D01*
G01Y159449D02*
X879515D01*
G03X879915Y159849I0J400D01*
G01Y160249D01*
G03X879146Y161018I-769J0D01*
G01X872650D01*
X872400Y160768D01*
G01Y162068D02*
X872500D01*
X872750Y161818D01*
X879146D01*
G02X880693Y160511I0J-1569D01*
G03X881950Y159449I1257J213D01*
G01X882284D01*
G01X892800Y263700D02*
X892508Y263408D01*
Y260527D01*
G03X892711Y260037I693J0D01*
G03X893194Y259837I483J483D01*
G01X893572D01*
G03X893953Y259995I0J539D01*
G01X893983Y260025D01*
G03X894195Y260537I-512J512D01*
G01Y261710D01*
X894095Y261810D01*
G01Y257873D02*
G02X893378Y258170I0J1014D01*
G01X892040Y259507D01*
G02X891708Y260310I803J802D01*
G01Y263492D01*
X891500Y263700D01*
G01X896700Y263894D02*
X896528Y263722D01*
X896445Y263687D01*
Y256590D01*
G03X896648Y256100I693J0D01*
G03X897131Y255900I483J483D01*
G01X897509D01*
G03X897890Y256058I0J539D01*
G01X897920Y256088D01*
G03X898132Y256600I-512J512D01*
G01Y257773D01*
X898032Y257873D01*
G01X895400Y263600D02*
X895645Y263355D01*
Y256373D01*
G03X895977Y255570I1135J-1D01*
G01X897315Y254233D01*
G03X898032Y253936I717J717D01*
G01X871203Y141083D02*
X871453Y141333D01*
X875655D01*
G02X876232Y141177I0J-1146D01*
G02X876753Y140515I-577J-990D01*
G02X876000Y139400I-833J-249D01*
G01X875289D01*
G02X874410Y139764I0J1243D01*
G01X872300Y137146D02*
X872400D01*
G02X873004Y137396I604J-605D01*
G01X879616D01*
G02X880099Y137230I1J-783D01*
G02X880336Y136923I-482J-617D01*
G02X880400Y136612I-719J-310D01*
G01Y135563D01*
G02X880214Y135114I-635J0D01*
G02X879763Y134927I-451J450D01*
G01X878797D01*
G02X878347Y135377I0J450D01*
G01Y135827D01*
G01X874410Y131890D02*
Y131845D01*
G03X874692Y131438I435J0D01*
G01X875045Y131305D01*
G03X876003Y131405I379J1006D01*
G01X876457Y131695D01*
G03X876511Y132815I-971J608D01*
G01X876509Y132818D01*
G03X875371Y133459I-1137J-688D01*
G01X873004D01*
G03X872400Y133209I0J-855D01*
G01X872300D01*
G01X871203Y142383D02*
X871303D01*
X871553Y142133D01*
X875655D01*
G02X876635Y141869I1J-1947D01*
G02X877738Y140903I-1931J-3318D01*
G02X878347Y139764I-3033J-2354D01*
G01X872300Y138446D02*
X872400D01*
X872650Y138196D01*
X879616D01*
G02X880592Y137861I2J-1584D01*
G02X881071Y137240I-977J-1249D01*
G03X881493Y136618I1837J792D01*
G01X882284Y135827D01*
G01X872300Y134509D02*
X872400D01*
X872650Y134259D01*
X875371D01*
G02X877184Y133250I2J-2129D01*
G01X877201Y133223D01*
G02X877224Y133179I-1713J-924D01*
G03X878347Y131890I3112J1577D01*
G01X872100Y145020D02*
X872350Y145270D01*
X879694D01*
G02X880614Y144350I0J-920D01*
G01Y143626D01*
G02X879481Y142493I-1133J0D01*
G01X879480D01*
G02X878347Y143626I0J1133D01*
G01Y143701D01*
G01X872100Y146320D02*
X872200D01*
X872450Y146070D01*
X879694D01*
G02X880919Y145563I1J-1732D01*
G01X881041Y145442D01*
G02X882284Y143701I-4595J-4595D01*
G01X904600Y263700D02*
X904319Y263419D01*
Y256590D01*
G03X904522Y256100I693J0D01*
G03X905005Y255900I483J483D01*
G01X905383D01*
G03X905764Y256058I0J539D01*
G01X905794Y256088D01*
G03X906006Y256600I-512J512D01*
G01Y257773D01*
X905906Y257873D01*
G01X900600Y263600D02*
X900382Y263382D01*
Y260527D01*
G03X900585Y260037I693J0D01*
G03X901068Y259837I483J483D01*
G01X901446D01*
G03X901827Y259995I0J539D01*
G01X901857Y260025D01*
G03X902069Y260537I-512J512D01*
G01Y261710D01*
X901969Y261810D01*
G01X903300Y263700D02*
X903519Y263481D01*
Y256373D01*
G03X903851Y255570I1135J-1D01*
G01X905189Y254233D01*
G03X905906Y253936I717J717D01*
G01X899300Y263600D02*
X899582Y263318D01*
Y260310D01*
G03X899914Y259507I1135J-1D01*
G01X901252Y258170D01*
G03X901969Y257873I717J717D01*
G01X913780Y261810D02*
X913880Y261710D01*
Y260537D01*
G02X913668Y260025I-724J0D01*
G01X913638Y259995D01*
G02X913257Y259837I-381J381D01*
G01X912879D01*
G02X912396Y260037I0J683D01*
G02X912193Y260527I490J490D01*
G01Y263493D01*
X912400Y263700D01*
G01X913780Y257873D02*
G02X913063Y258170I0J1014D01*
G01X911725Y259507D01*
G02X911393Y260310I803J802D01*
G01Y263407D01*
X911100Y263700D01*
G01X871900Y117460D02*
X872000D01*
X872125Y117585D01*
G02X872427Y117710I302J-302D01*
G01X877272D01*
G02X878347Y116142I0J-1153D01*
G01X882284Y120079D02*
X882297Y120438D01*
G03X882118Y120977I-814J29D01*
G01X882048Y121064D01*
G03X881736Y121214I-312J-249D01*
G01X881307D01*
G03X881193Y121201I2J-524D01*
G03X880899Y121019I113J-512D01*
G03X880732Y120566I530J-453D01*
G01Y114620D01*
G03X880941Y114117I712J1D01*
G01X880957Y114100D01*
G01X871900Y118760D02*
X872000D01*
X872125Y118635D01*
G03X872427Y118510I302J302D01*
G01X877947D01*
G03X878347Y118910I0J400D01*
G01Y120079D01*
G01X882300Y124032D02*
G02X881838Y122379I-3188J0D01*
G02X881019Y121983I-1248J1536D01*
G03X880293Y121544I288J-1295D01*
G03X879932Y120616I1137J-976D01*
G01Y114620D01*
G02X879759Y114202I-591J0D01*
G01X879657Y114100D01*
G01X916400Y263800D02*
X916130Y263530D01*
Y256590D01*
G03X916333Y256100I693J0D01*
G03X916816Y255900I483J483D01*
G01X917194D01*
G03X917575Y256058I0J539D01*
G01X917605Y256088D01*
G03X917817Y256600I-512J512D01*
G01Y257773D01*
X917717Y257873D01*
G01X915100Y263800D02*
X915330Y263570D01*
Y256373D01*
G03X915662Y255570I1135J-1D01*
G01X917000Y254233D01*
G03X917717Y253936I717J717D01*
G01X921654Y261810D02*
X921754Y261710D01*
Y260537D01*
G02X921542Y260025I-724J0D01*
G01X921512Y259995D01*
G02X921131Y259837I-381J381D01*
G01X920753D01*
G02X920270Y260037I0J683D01*
G02X920067Y260527I490J490D01*
G01Y263467D01*
X920300Y263700D01*
G01X921654Y257873D02*
G02X920937Y258170I0J1014D01*
G01X919599Y259507D01*
G02X919267Y260310I803J802D01*
G01Y263433D01*
X919000Y263700D01*
G01X925591Y257873D02*
X925691Y257773D01*
Y256600D01*
G02X925479Y256088I-724J0D01*
G01X925449Y256058D01*
G02X925068Y255900I-381J381D01*
G01X924690D01*
G02X924207Y256100I0J683D01*
G02X924004Y256590I490J490D01*
G01Y263504D01*
X924200Y263700D01*
G01X925591Y253936D02*
G02X924874Y254233I0J1014D01*
G01X923536Y255570D01*
G02X923204Y256373I803J802D01*
G01Y263396D01*
X922900Y263700D01*
G01X882872Y176534D02*
X882972D01*
X883222Y176784D01*
X938284D01*
X938835Y176233D01*
G02X938952Y175950I-284J-283D01*
G01Y147068D01*
G03X939487Y145776I1828J0D01*
G01X939488Y145775D01*
X939611Y145653D01*
G03X940538Y145269I928J930D01*
G01X941836D01*
G02Y143701I0J-784D01*
G01X941339D01*
G01X882872Y177834D02*
X882972D01*
X883222Y177584D01*
X938616D01*
X938850Y177350D01*
X939402Y176799D01*
G02X939752Y175950I-851J-848D01*
G01Y147068D01*
G03X940053Y146342I1027J1D01*
G01X940175Y146221D01*
X940176Y146220D01*
G03X940539Y146069I364J363D01*
G01X940939D01*
G03X941339Y146469I0J400D01*
G01Y147638D01*
G01X928100Y263700D02*
X927941Y263541D01*
Y260527D01*
G03X928144Y260037I693J0D01*
G03X928627Y259837I483J483D01*
G01X929005D01*
G03X929386Y259995I0J539D01*
G01X929416Y260025D01*
G03X929628Y260537I-512J512D01*
G01Y261710D01*
X929528Y261810D01*
G01X933465Y253936D02*
G02X932748Y254233I0J1014D01*
G01X931410Y255570D01*
G02X931078Y256373I803J802D01*
G01Y263522D01*
X930800Y263800D01*
G01X926800Y263700D02*
X927141Y263359D01*
Y260310D01*
G03X927473Y259507I1135J-1D01*
G01X928811Y258170D01*
G03X929528Y257873I717J717D01*
G01X933465D02*
X933565Y257773D01*
Y256600D01*
G02X933353Y256088I-724J0D01*
G01X933323Y256058D01*
G02X932942Y255900I-381J381D01*
G01X932564D01*
G02X932081Y256100I0J683D01*
G02X931878Y256590I490J490D01*
G01Y263578D01*
X932100Y263800D01*
G01X941339Y257873D02*
X941439Y257773D01*
Y256600D01*
G02X941227Y256088I-724J0D01*
G01X941197Y256058D01*
G02X940816Y255900I-381J381D01*
G01X940438D01*
G02X939955Y256100I0J683D01*
G02X939752Y256590I490J490D01*
G01Y263552D01*
X940000Y263800D01*
G01X936100D02*
X935815Y263515D01*
Y260527D01*
G03X936018Y260037I693J0D01*
G03X936501Y259837I483J483D01*
G01X936879D01*
G03X937260Y259995I0J539D01*
G01X937290Y260025D01*
G03X937502Y260537I-512J512D01*
G01Y261710D01*
X937402Y261810D01*
G01X941339Y253936D02*
G02X940622Y254233I0J1014D01*
G01X939284Y255570D01*
G02X938952Y256373I803J802D01*
G01Y263548D01*
X938700Y263800D01*
G01X934800D02*
X935015Y263585D01*
Y260310D01*
G03X935347Y259507I1135J-1D01*
G01X936685Y258170D01*
G03X937402Y257873I717J717D01*
G01X888840Y114900D02*
Y115000D01*
G02X888590Y115604I605J604D01*
G01Y120550D01*
G02X888757Y121003I697J0D01*
G02X889165Y121198I408J-329D01*
G01X889595D01*
G02X890158Y120500I-151J-698D01*
G01Y120079D01*
G01X892751Y113905D02*
Y114005D01*
G02X892501Y114609I605J604D01*
G01Y116568D01*
G02X892748Y117164I843J0D01*
G01X892750Y117166D01*
G02X893342Y117411I592J-593D01*
G01X893402D01*
G02X893892Y117208I0J-693D01*
G01X893978Y117122D01*
G02X894095Y116839I-284J-283D01*
G01Y116142D01*
G01X896714Y112867D02*
Y112967D01*
G02X896464Y113571I605J604D01*
G01Y120500D01*
G02X896669Y120993I698J-1D01*
G01X896756Y121080D01*
G02X897039Y121198I284J-282D01*
G01X897469D01*
G02X898032Y120500I-151J-698D01*
G01Y120079D01*
G01X901969Y116142D02*
Y116500D01*
G03X901736Y117065I-802J0D01*
G01X901735Y117066D01*
G03X901168Y117300I-566J-567D01*
G01X901059D01*
G03X900939Y117289I2J-683D01*
G03X900376Y116617I120J-673D01*
G01Y113132D01*
G03X900626Y112528I855J0D01*
G01Y112428D01*
G01X890158Y124016D02*
Y122853D01*
G02X889457Y121998I-872J0D01*
G01X889164D01*
G03X888151Y121528I0J-1327D01*
G03X887790Y120600I1137J-976D01*
G01Y115250D01*
X887540Y115000D01*
Y114900D01*
G01X891451Y113905D02*
Y114005D01*
X891701Y114255D01*
Y116568D01*
G02X892182Y117730I1643J1D01*
G01X892184Y117732D01*
G02X893342Y118211I1157J-1159D01*
G01X893610D01*
G03X893953Y118353I0J485D01*
G01X893978Y118378D01*
G03X894095Y118661I-284J283D01*
G01Y120079D01*
G01X895414Y112867D02*
Y112967D01*
X895664Y113217D01*
Y120501D01*
G02X896103Y121560I1499J-1D01*
G01X896189Y121646D01*
G02X897038Y121998I849J-849D01*
G01X897633D01*
G03X898032Y122397I0J399D01*
G01Y124016D01*
G01X899326Y112428D02*
Y112528D01*
X899576Y112778D01*
Y116617D01*
G02X900797Y118077I1483J0D01*
G02X901057Y118100I260J-1461D01*
G01X901167D01*
G03X901969Y118731I0J825D01*
G01Y120079D01*
G01X953149Y257873D02*
X953249Y257773D01*
Y256600D01*
G02X953037Y256088I-724J0D01*
G01X953007Y256058D01*
G02X952626Y255900I-381J381D01*
G01X952248D01*
G02X951765Y256100I0J683D01*
G02X951562Y256590I490J490D01*
G01Y263362D01*
X951800Y263600D01*
G01X953149Y253936D02*
G02X952432Y254233I0J1014D01*
G01X951094Y255570D01*
G02X950762Y256373I803J802D01*
G01Y263338D01*
X950500Y263600D01*
G01X957086Y257873D02*
G02X956369Y258170I0J1014D01*
G01X955031Y259507D01*
G02X954699Y260310I803J802D01*
G01Y263201D01*
X954400Y263500D01*
G01X883200Y168900D02*
X902585D01*
X903519Y167966D01*
Y143895D01*
X905906Y141508D01*
Y139764D01*
G01X882118Y172825D02*
X882903Y173610D01*
X906881D01*
X908256Y172235D01*
Y151732D01*
X905906Y149382D01*
Y147638D01*
G01X879495Y164800D02*
X879631Y164936D01*
X898675D01*
X899600Y164011D01*
Y138808D01*
X901031Y137377D01*
X902612D01*
X903519Y136470D01*
Y136021D01*
X905906Y133634D01*
Y131890D01*
G01X961023Y257873D02*
X961123Y257773D01*
Y256600D01*
G02X960911Y256088I-724J0D01*
G01X960881Y256058D01*
G02X960500Y255900I-381J381D01*
G01X960122D01*
G02X959639Y256100I0J683D01*
G02X959436Y256590I490J490D01*
G01Y263536D01*
X959700Y263800D01*
G01X957086Y261810D02*
X957186Y261710D01*
Y260537D01*
G02X956974Y260025I-724J0D01*
G01X956944Y259995D01*
G02X956563Y259837I-381J381D01*
G01X956185D01*
G02X955702Y260037I0J683D01*
G02X955499Y260527I490J490D01*
G01Y263299D01*
X955700Y263500D01*
G01X961023Y253936D02*
G02X960306Y254233I0J1014D01*
G01X958968Y255570D01*
G02X958636Y256373I803J802D01*
G01Y263564D01*
X958400Y263800D01*
G01X964960Y261810D02*
X965060Y261710D01*
Y260537D01*
G02X964848Y260025I-724J0D01*
G01X964818Y259995D01*
G02X964437Y259837I-381J381D01*
G01X964059D01*
G02X963576Y260037I0J683D01*
G02X963373Y260527I490J490D01*
G01Y263373D01*
X963600Y263600D01*
G01X964960Y257873D02*
G02X964243Y258170I0J1014D01*
G01X962905Y259507D01*
G02X962573Y260310I803J802D01*
G01Y263327D01*
X962300Y263600D01*
G01X883363Y169864D02*
X883526Y169701D01*
X902916D01*
X904319Y168298D01*
Y146281D01*
X905906Y144694D01*
Y143701D01*
G01Y135827D02*
X905776D01*
X903389Y138214D01*
X901326D01*
X900400Y139140D01*
Y164343D01*
X898970Y165773D01*
X881127D01*
X880400Y166500D01*
G01X972834Y261810D02*
X972934Y261710D01*
Y260537D01*
G02X972722Y260025I-724J0D01*
G01X972692Y259995D01*
G02X972311Y259837I-381J381D01*
G01X971933D01*
G02X971450Y260037I0J683D01*
G02X971247Y260527I490J490D01*
G01Y263547D01*
X971400Y263700D01*
G01X968897Y257873D02*
X968997Y257773D01*
Y256600D01*
G02X968785Y256088I-724J0D01*
G01X968755Y256058D01*
G02X968374Y255900I-381J381D01*
G01X967996D01*
G02X967513Y256100I0J683D01*
G02X967310Y256590I490J490D01*
G01Y263610D01*
X967500Y263800D01*
G01X972834Y257873D02*
G02X972117Y258170I0J1014D01*
G01X970779Y259507D01*
G02X970447Y260310I803J802D01*
G01Y263353D01*
X970100Y263700D01*
G01X968897Y253936D02*
G02X968180Y254233I0J1014D01*
G01X966842Y255570D01*
G02X966510Y256373I803J802D01*
G01Y263490D01*
X966200Y263800D01*
G01X976771Y257873D02*
X976871Y257773D01*
Y256600D01*
G02X976659Y256088I-724J0D01*
G01X976629Y256058D01*
G02X976248Y255900I-381J381D01*
G01X975870D01*
G02X975387Y256100I0J683D01*
G02X975184Y256590I490J490D01*
G01Y263384D01*
X975400Y263600D01*
G01X976771Y253936D02*
G02X976054Y254233I0J1014D01*
G01X974716Y255570D01*
G02X974384Y256373I803J802D01*
G01Y263316D01*
X974100Y263600D01*
G01X911000Y114500D02*
X911393Y114893D01*
Y130340D01*
X909843Y131890D01*
G01X883745Y172205D02*
X884350Y172810D01*
X906549D01*
X907456Y171903D01*
Y157062D01*
X905906Y155512D01*
G01X991200Y263994D02*
X990932Y263726D01*
Y260527D01*
G03X991135Y260037I693J0D01*
G03X991618Y259837I483J483D01*
G01X991996D01*
G03X992377Y259995I0J539D01*
G01X992407Y260025D01*
G03X992619Y260537I-512J512D01*
G01Y261710D01*
X992519Y261810D01*
G01X988582Y257873D02*
X988682Y257773D01*
Y256600D01*
G02X988470Y256088I-724J0D01*
G01X988440Y256058D01*
G02X988059Y255900I-381J381D01*
G01X987681D01*
G02X987198Y256100I0J683D01*
G02X986995Y256590I490J490D01*
G01Y263841D01*
X987200Y263998D01*
Y264430D01*
G01X980708Y261810D02*
X980808Y261710D01*
Y260537D01*
G02X980596Y260025I-724J0D01*
G01X980566Y259995D01*
G02X980185Y259837I-381J381D01*
G01X979807D01*
G02X979324Y260037I0J683D01*
G02X979121Y260527I490J490D01*
G01Y263321D01*
X979300Y263500D01*
G01X989900Y264288D02*
Y264188D01*
X990132Y264058D01*
Y260310D01*
G03X990464Y259507I1135J-1D01*
G01X991802Y258170D01*
G03X992519Y257873I717J717D01*
G01X988582Y253936D02*
G02X987865Y254233I0J1014D01*
G01X986527Y255570D01*
G02X986195Y256373I803J802D01*
G01Y263841D01*
X985900Y264136D01*
G01X980708Y257873D02*
G02X979991Y258170I0J1014D01*
G01X978653Y259507D01*
G02X978321Y260310I803J802D01*
G01Y263179D01*
X978000Y263500D01*
G01X931000Y110600D02*
X931915Y111515D01*
Y114100D01*
X931929Y114114D01*
Y114818D01*
X931915Y114832D01*
Y147285D01*
X931078Y148122D01*
Y153522D01*
X929528Y155072D01*
Y155512D01*
G01X925591Y139764D02*
Y139609D01*
X927141Y138059D01*
Y118341D01*
X926700Y117900D01*
G01X925591Y143701D02*
X926699D01*
X929086Y141314D01*
X930171D01*
X931078Y140407D01*
Y114466D01*
G01X925591Y147638D02*
X923500Y145547D01*
Y142500D01*
X924100Y141900D01*
X926934D01*
X927941Y140893D01*
Y114220D01*
X927921Y114200D01*
G01X984645Y131890D02*
X982288Y129533D01*
Y127270D01*
X980618Y125600D01*
X979071D01*
X978371Y124900D01*
G01X933465Y155512D02*
Y154435D01*
X935100Y152800D01*
Y113800D01*
G01X985400Y118100D02*
X986195Y118895D01*
Y125500D01*
X987098Y126403D01*
X989225D01*
X990132Y127310D01*
Y140407D01*
X988375Y142164D01*
X987926D01*
X987032Y143058D01*
Y145251D01*
X988582Y146801D01*
Y147638D01*
G01X986000Y116900D02*
X987000Y117900D01*
Y124996D01*
X987607Y125603D01*
X989735D01*
X990932Y126800D01*
Y140739D01*
X990586Y141086D01*
X988582Y143090D01*
Y143701D01*
G01X991173Y111771D02*
X990934Y112010D01*
Y116725D01*
G02X991533Y117324I599J0D01*
G02X992519Y115742I0J-1098D01*
G01X996456Y120079D02*
X996728Y120481D01*
G03X996477Y121780I-776J524D01*
G01X996476Y121781D01*
G03X995407Y121852I-575J-575D01*
G03X995176Y121529I6123J-4623D01*
G03X994891Y120599I1375J-930D01*
G01Y114094D01*
X994550Y113753D01*
Y111060D01*
X994800Y110810D01*
Y110710D01*
G01X1000393Y116142D02*
G03X1001100Y116849I0J707D01*
G01Y117910D01*
G03X1000618Y118392I-482J0D01*
G01X1000137D01*
G03X999630Y118182I0J-717D01*
G01X999628D01*
X999064Y117618D01*
G03X998250Y115600I2094J-2018D01*
G01Y114650D01*
X998500Y114400D01*
Y114300D01*
G01X1004330Y120079D02*
G03X1004700Y120972I-893J893D01*
G03X1003772Y121900I-928J0D01*
G01X1003769D01*
G03X1003105Y121625I0J-939D01*
G03X1002774Y120600I1425J-1026D01*
G01Y119011D01*
G03X1003046Y118354I929J0D01*
G01X1003318Y118082D01*
Y117450D01*
G01X1008267Y116142D02*
Y117831D01*
G03X1007502Y118148I-448J0D01*
G01X1007042Y117688D01*
G03X1006711Y116663I1425J-1026D01*
G01Y113982D01*
X1007368Y113325D01*
Y111410D01*
X1007618Y111160D01*
Y111060D01*
G01X989873Y111648D02*
X990134Y111909D01*
Y116725D01*
G02X991533Y118124I1399J0D01*
G01X992119D01*
G03X992519Y118524I0J400D01*
G01Y120079D01*
G01X993500Y110710D02*
Y110810D01*
X993750Y111060D01*
Y114085D01*
X994091Y114426D01*
Y120599D01*
G02X994513Y121977I2461J0D01*
G02X996456Y124016I7020J-4744D01*
G01X1000393Y120079D02*
X998493Y118179D01*
G03X997450Y115600I2666J-2578D01*
G01Y114650D01*
X997200Y114400D01*
Y114300D01*
G01X1004330Y124016D02*
Y123998D01*
X1002620Y122286D01*
G03X1002455Y122092I1116J-1116D01*
G03X1001974Y120600I2075J-1493D01*
G01Y118144D01*
X1002018Y118100D01*
Y117500D01*
G01X1006318Y111060D02*
Y111160D01*
X1006568Y111410D01*
Y112993D01*
X1005911Y113650D01*
Y116663D01*
G02X1006392Y118155I2556J-1D01*
G02X1006660Y118471I2077J-1490D01*
G01X1006927Y118739D01*
X1008267Y120079D01*
G01Y261810D02*
X1008367Y261710D01*
Y260537D01*
G02X1008155Y260025I-724J0D01*
G01X1008125Y259995D01*
G02X1007744Y259837I-381J381D01*
G01X1007366D01*
G02X1006883Y260037I0J683D01*
G02X1006680Y260527I490J490D01*
G01Y263280D01*
X1006900Y263500D01*
G01X1004330Y257873D02*
X1004430Y257773D01*
Y256600D01*
G02X1004218Y256088I-724J0D01*
G01X1004188Y256058D01*
G02X1003807Y255900I-381J381D01*
G01X1003429D01*
G02X1002946Y256100I0J683D01*
G02X1002743Y256590I490J490D01*
G01Y263043D01*
X1003000Y263300D01*
G01X1000393Y261810D02*
Y260338D01*
G02X1000251Y259995I-485J0D01*
G02X999870Y259837I-381J381D01*
G01X999492D01*
G02X999009Y260037I0J683D01*
G02X998806Y260527I490J490D01*
G01Y263106D01*
X999150Y263450D01*
G01X996456Y257873D02*
G02X996700Y257284I-589J-589D01*
G01Y256800D01*
G02X996449Y256193I-859J0D01*
G01X996314Y256058D01*
G02X995933Y255900I-381J381D01*
G01X995555D01*
G02X995072Y256100I0J683D01*
G02X994869Y256590I490J490D01*
G01Y263369D01*
X995100Y263600D01*
G01X1008267Y257873D02*
G02X1007550Y258170I0J1014D01*
G01X1006212Y259507D01*
G02X1005880Y260310I803J802D01*
G01Y263220D01*
X1005600Y263500D01*
G01X1004330Y253936D02*
G02X1003613Y254233I0J1014D01*
G01X1002275Y255570D01*
G02X1001943Y256373I803J802D01*
G01Y263057D01*
X1001700Y263300D01*
G01X1000393Y257873D02*
G02X999676Y258170I0J1014D01*
G01X998338Y259507D01*
G02X998006Y260310I803J802D01*
G01Y263488D01*
X997850Y263644D01*
Y263694D01*
G01X996456Y253936D02*
G02X995739Y254233I0J1014D01*
G01X994401Y255570D01*
G02X994069Y256373I803J802D01*
G01Y263331D01*
X993800Y263600D01*
G01X1011600Y111530D02*
Y111630D01*
X1011350Y111880D01*
Y115313D01*
X1010648Y116015D01*
Y120600D01*
G02X1010979Y121625I1756J-1D01*
G01X1011190Y121835D01*
X1011386Y122031D01*
G02X1011974I294J-294D01*
G02X1012204Y121476I-555J-555D01*
G01Y120079D01*
G01X1010300Y111530D02*
Y111630D01*
X1010550Y111880D01*
Y114981D01*
X1009848Y115683D01*
Y120600D01*
G02X1010329Y122092I2556J-1D01*
G02X1010597Y122408I2077J-1490D01*
G01X1012204Y124016D01*
G01X1024703Y138739D02*
X1024093D01*
X1023562Y138208D01*
X1019926D01*
X1019679Y138315D01*
G02X1019300Y138977I389J662D01*
G01Y138986D01*
G02X1020078Y139764I778J0D01*
G01X1018874Y113200D02*
X1018500D01*
X1018000Y112700D01*
X1016085D01*
G02X1014585Y114200I0J1500D01*
G01Y116663D01*
G02X1015206Y117545I937J0D01*
G02X1015522Y117600I316J-882D01*
G02X1016113Y117350I-1J-825D01*
G01X1016141Y117322D01*
G02Y116142I-589J-590D01*
G01X1024893Y130978D02*
X1024793D01*
X1024543Y130728D01*
X1022278D01*
X1021884Y130334D01*
X1019978D01*
G02Y131890I0J778D01*
G01X1020078D01*
G01X1021533Y134772D02*
X1020972D01*
X1020471Y134271D01*
X1016041D01*
G02Y135827I0J778D01*
G01X1016141D01*
G01X1024703Y137439D02*
X1024672Y137408D01*
X1019737D01*
X1019719Y137426D01*
X1017545Y138360D01*
X1016141Y139764D01*
G01X1023000Y141372D02*
X1022973Y141345D01*
X1015363D01*
G02X1014856Y141412I-2J1939D01*
G02X1013992Y141913I508J1871D01*
G01X1012204Y143701D01*
G01X1018800Y111900D02*
X1016085D01*
G02X1013785Y114200I0J2300D01*
G01Y116663D01*
G02X1014936Y118299I1738J0D01*
G02X1014988Y118317I594J-1633D01*
G03X1016141Y119909I-523J1592D01*
G01Y120079D01*
G01Y131890D02*
G02X1017553Y131305I0J-1997D01*
G01X1018966Y129892D01*
G03X1019830Y129534I864J864D01*
G01X1022216D01*
X1022610Y129928D01*
X1024543D01*
X1024793Y129678D01*
X1024893D01*
G01X1021600Y133472D02*
X1020804D01*
X1020803Y133471D01*
X1015363D01*
G02X1013992Y134039I0J1939D01*
G01X1012204Y135827D01*
G01X1023100Y142672D02*
X1022340D01*
X1022076Y142408D01*
G02X1021440Y142145I-636J638D01*
G01X1015932D01*
G02X1015459Y142341I0J669D01*
G02X1015263Y142814I473J473D01*
G01Y142923D01*
G02X1016141Y143701I781J3D01*
G01X1022580Y150519D02*
X1022373Y150312D01*
G02X1021666Y150019I-707J706D01*
G01X1015977D01*
G02X1015263Y150733I0J714D01*
G01Y150797D01*
G02X1016141Y151575I781J3D01*
G01X1021800Y160273D02*
X1020542D01*
X1018559Y158290D01*
G02X1017600Y157893I-959J959D01*
G01X1015958D01*
G02X1015263Y158671I0J699D01*
G02X1016141Y159449I781J3D01*
G01X1023192Y168700D02*
X1022546Y169346D01*
G03X1021993Y169657I-834J-836D01*
G03X1021711Y169692I-285J-1146D01*
G01X1020630D01*
G03X1020491Y169684I1J-1222D01*
G03X1019921Y169465I139J-1214D01*
G03X1019766Y169334I709J-996D01*
G01X1019660Y169228D01*
G03X1019400Y168600I628J-628D01*
G03X1019824Y167578I1446J1D01*
G01X1020078Y167323D01*
G01X1016141Y171260D02*
X1015479D01*
G02X1014900Y171500I0J819D01*
G01X1014813Y171586D01*
G02X1014730Y171691I384J389D01*
G02X1014725Y171698I442J321D01*
G02X1014708Y171730I474J273D01*
G02X1014662Y171871I492J239D01*
G02X1014656Y171916I539J95D01*
G01Y171980D01*
G02Y171994I688J7D01*
G02X1014669Y172114I688J-14D01*
G02X1015104Y172625I675J-134D01*
G02X1016024Y172791I922J-2475D01*
G01X1016301D01*
X1016349Y172792D01*
G02X1016600Y172800I258J-4155D01*
G01X1022017D01*
G02X1022500Y172600I0J-683D01*
G01X1020078Y175197D02*
X1019824Y175452D01*
G02X1019400Y176474I1022J1023D01*
G02X1019660Y177102I888J0D01*
G01X1019766Y177208D01*
G02X1019921Y177339I864J-865D01*
G02X1020630Y177566I710J-996D01*
G01X1021711D01*
G02X1021993Y177531I-3J-1181D01*
G02X1022546Y177220I-281J-1147D01*
G01X1023192Y176574D01*
G01X1022719Y149219D02*
X1015363D01*
G02X1014856Y149286I-2J1939D01*
G02X1013992Y149787I508J1871D01*
G01X1012204Y151575D01*
G01Y159449D02*
X1013992Y157661D01*
G03X1014856Y157160I1372J1370D01*
G03X1015363Y157093I505J1872D01*
G01X1017600D01*
G03X1019125Y157724I1J2156D01*
G01X1020374Y158973D01*
X1021800D01*
G01X1023731Y170000D02*
G03X1022543Y170492I-1188J-1188D01*
G01X1020629D01*
G03X1020400Y170479I0J-2022D01*
G03X1019456Y170117I229J-2009D01*
G03X1019196Y169897I1186J-1666D01*
G01X1019008Y169709D01*
X1018550Y169250D01*
X1016964Y167664D01*
G02X1016141Y167323I-823J823D01*
G01X1012204Y171260D02*
X1012669Y170795D01*
G03X1012898Y170700I229J229D01*
G03X1013094Y170723I1J839D01*
G03X1013673Y171218I-196J816D01*
G01X1013764Y171437D01*
G03X1013833Y171784I-838J347D01*
G01Y171980D01*
G02X1013839Y172041I317J0D01*
G01X1013884Y172269D01*
G02X1014825Y173375I1460J-289D01*
G02X1016023Y173591I1200J-3225D01*
G01X1016292D01*
X1016317Y173592D01*
G02X1016599Y173600I282J-4955D01*
G01X1021876D01*
G03X1022600Y173900I0J1024D01*
G01X1016141Y175197D02*
G03X1016964Y175538I0J1164D01*
G01X1019196Y177771D01*
G02X1019456Y177991I1446J-1446D01*
G02X1020629Y178366I1173J-1647D01*
G01X1022543D01*
G02X1023731Y177874I0J-1680D01*
G01X1016141Y179134D02*
X1015479D01*
G02X1014900Y179374I0J819D01*
G01X1014813Y179460D01*
G02X1014730Y179565I384J389D01*
G02X1014725Y179572I442J321D01*
G02X1014708Y179604I474J273D01*
G02X1014662Y179745I492J239D01*
G02X1014656Y179790I539J95D01*
G01Y179854D01*
G02Y179868I688J7D01*
G02X1014669Y179988I688J-14D01*
G02X1015104Y180499I675J-134D01*
G02X1016024Y180665I922J-2475D01*
G01X1022139D01*
G02X1022600Y180474I0J-652D01*
G01Y192284D02*
G03X1022139Y192475I-461J-461D01*
G01X1016024D01*
G03X1015104Y192309I2J-2641D01*
G03X1014669Y191798I240J-645D01*
G03X1014656Y191678I675J-134D01*
G03Y191664I688J-7D01*
G01Y191600D01*
G03X1014662Y191555I545J50D01*
G03X1014708Y191414I538J98D01*
G03X1014725Y191382I491J241D01*
G03X1014730Y191375I447J314D01*
G03X1014813Y191270I467J284D01*
G01X1014900Y191184D01*
G03X1015479Y190944I579J579D01*
G01X1016141D01*
G01X1020078Y194881D02*
X1019824Y195136D01*
G02X1019400Y196158I1022J1023D01*
G02X1019660Y196786I888J0D01*
G01X1019766Y196892D01*
G02X1019921Y197023I865J-866D01*
G02X1020630Y197250I710J-997D01*
G01X1021711D01*
G02X1021993Y197215I-3J-1181D01*
G02X1022546Y196904I-281J-1147D01*
G01X1023192Y196258D01*
G01X1022600Y200158D02*
G03X1022139Y200349I-461J-461D01*
G01X1016024D01*
G03X1015104Y200183I2J-2641D01*
G03X1014669Y199672I240J-645D01*
G03X1014656Y199552I675J-134D01*
G03Y199538I688J-7D01*
G01Y199474D01*
G03X1014662Y199429I545J50D01*
G03X1014708Y199288I538J98D01*
G03X1014725Y199256I491J241D01*
G03X1014730Y199249I447J314D01*
G03X1014813Y199144I467J284D01*
G01X1014900Y199058D01*
G03X1015479Y198818I579J579D01*
G01X1016141D01*
G01X1020078Y206692D02*
X1019824Y206947D01*
G02X1019400Y207969I1022J1023D01*
G02X1019660Y208597I888J0D01*
G01X1019766Y208703D01*
G02X1019921Y208834I865J-866D01*
G02X1020630Y209061I710J-997D01*
G01X1021711D01*
G02X1021993Y209026I-3J-1181D01*
G02X1022546Y208715I-281J-1147D01*
G01X1023192Y208069D01*
G01X1012204Y179134D02*
X1012669Y178669D01*
G03X1012898Y178574I229J229D01*
G03X1013094Y178597I1J839D01*
G03X1013673Y179092I-196J816D01*
G01X1013764Y179311D01*
G03X1013833Y179658I-838J347D01*
G01Y179854D01*
G02X1013839Y179915I317J0D01*
G01X1013884Y180143D01*
G02X1014825Y181249I1460J-289D01*
G02X1016023Y181465I1200J-3225D01*
G01X1021946D01*
G03X1022600Y181774I0J847D01*
G01Y193584D02*
G02X1021847Y193275I-753J763D01*
G01X1016023D01*
G03X1014825Y193059I2J-3441D01*
G03X1013884Y191953I519J-1395D01*
G01X1013839Y191725D01*
G03X1013833Y191664I311J-61D01*
G01Y191468D01*
G02X1013764Y191121I-907J0D01*
G01X1013673Y190902D01*
G02X1013094Y190407I-775J321D01*
G02X1012898Y190384I-195J816D01*
G02X1012669Y190479I0J324D01*
G01X1012204Y190944D01*
G01X1023731Y197558D02*
G03X1022543Y198050I-1188J-1188D01*
G01X1020629D01*
G03X1019456Y197675I0J-2022D01*
G03X1019196Y197455I1186J-1666D01*
G01X1016964Y195222D01*
G02X1016141Y194881I-823J823D01*
G01X1022600Y201458D02*
G02X1021754Y201149I-846J1004D01*
G01X1016023D01*
G03X1014825Y200933I2J-3441D01*
G03X1013884Y199827I519J-1395D01*
G01X1013839Y199599D01*
G03X1013833Y199538I311J-61D01*
G01Y199342D01*
G02X1013764Y198995I-907J0D01*
G01X1013673Y198776D01*
G02X1013094Y198281I-775J321D01*
G02X1012898Y198258I-195J816D01*
G02X1012669Y198353I0J324D01*
G01X1012204Y198818D01*
G01X1016141Y206692D02*
G03X1016964Y207033I0J1164D01*
G01X1019196Y209266D01*
G02X1019456Y209486I1446J-1446D01*
G02X1020629Y209861I1173J-1647D01*
G01X1022543D01*
G02X1023731Y209369I0J-1680D01*
G01X1016141Y210629D02*
X1015479D01*
G02X1014900Y210869I0J819D01*
G01X1014813Y210955D01*
G02X1014730Y211060I384J389D01*
G02X1014725Y211067I442J321D01*
G02X1014708Y211099I474J273D01*
G02X1014662Y211240I492J239D01*
G02X1014656Y211285I539J95D01*
G01Y211349D01*
G02Y211363I688J7D01*
G02X1014669Y211483I688J-14D01*
G02X1015104Y211994I675J-134D01*
G02X1016024Y212160I922J-2475D01*
G01X1022139D01*
G02X1022600Y211969I0J-652D01*
G01X1020078Y214566D02*
X1019824Y214821D01*
G02X1019400Y215843I1022J1023D01*
G02X1019660Y216471I888J0D01*
G01X1019766Y216577D01*
G02X1020630Y216935I865J-866D01*
G01X1021711D01*
G02X1021993Y216900I-3J-1181D01*
G02X1022546Y216589I-281J-1147D01*
G01X1023192Y215943D01*
G01X1022600Y219843D02*
G03X1022139Y220034I-461J-461D01*
G01X1016024D01*
G03X1015104Y219868I2J-2641D01*
G03X1014669Y219357I240J-645D01*
G03X1014656Y219237I675J-134D01*
G03Y219223I688J-7D01*
G01Y219159D01*
G03X1014662Y219114I545J50D01*
G03X1014708Y218973I538J98D01*
G03X1014725Y218941I491J241D01*
G03X1014730Y218934I447J314D01*
G03X1014813Y218829I467J284D01*
G01X1014900Y218743D01*
G03X1015479Y218503I579J579D01*
G01X1016141D01*
G01X1020078Y222440D02*
X1019824Y222695D01*
G02X1019400Y223717I1022J1023D01*
G02X1019660Y224345I888J0D01*
G01X1019766Y224451D01*
G02X1020630Y224809I865J-866D01*
G01X1021711D01*
G02X1021993Y224774I-3J-1181D01*
G02X1022546Y224463I-281J-1147D01*
G01X1023192Y223817D01*
G01X1016141Y226377D02*
X1015479D01*
G02X1014900Y226617I0J819D01*
G01X1014813Y226703D01*
G02X1014730Y226808I384J389D01*
G02X1014725Y226815I442J321D01*
G02X1014708Y226847I474J273D01*
G02X1014662Y226988I492J239D01*
G02X1014656Y227033I539J95D01*
G01Y227097D01*
G02Y227111I688J7D01*
G02X1014669Y227231I688J-14D01*
G02X1015104Y227742I675J-134D01*
G02X1016024Y227908I922J-2475D01*
G01X1022139D01*
G02X1022600Y227717I0J-652D01*
G01X1020078Y230314D02*
X1019824Y230569D01*
G02X1019400Y231591I1022J1023D01*
G02X1019660Y232219I888J0D01*
G01X1019766Y232325D01*
G02X1020630Y232683I865J-866D01*
G01X1021622D01*
G02X1022259Y232419I0J-901D01*
G01X1022627Y232051D01*
G01X1016141Y234251D02*
X1015479D01*
G02X1014900Y234491I0J819D01*
G01X1014813Y234577D01*
G02X1014730Y234682I384J389D01*
G02X1014725Y234689I442J321D01*
G02X1014708Y234719I468J285D01*
G02Y234721I547J1D01*
G02X1014662Y234862I492J239D01*
G02X1014656Y234907I539J95D01*
G01Y234971D01*
G02Y234985I688J7D01*
G02X1014669Y235105I688J-14D01*
G02X1015104Y235616I675J-134D01*
G02X1016024Y235782I920J-2466D01*
G01X1022747D01*
G03X1024060Y236326I0J1857D01*
G01X1012204Y210629D02*
X1012669Y210164D01*
G03X1012898Y210069I229J229D01*
G03X1013094Y210092I1J839D01*
G03X1013673Y210587I-196J816D01*
G01X1013764Y210806D01*
G03X1013833Y211153I-838J347D01*
G01Y211349D01*
G02X1013839Y211410I317J0D01*
G01X1013884Y211638D01*
G02X1014825Y212744I1460J-289D01*
G02X1016023Y212960I1200J-3225D01*
G01X1021854D01*
G03X1022600Y213269I0J1055D01*
G01X1016141Y214566D02*
G03X1016964Y214907I0J1164D01*
G01X1019196Y217140D01*
G02X1019456Y217360I1446J-1446D01*
G02X1020629Y217735I1173J-1647D01*
G01X1022543D01*
G02X1023731Y217243I0J-1680D01*
G01X1022600Y221143D02*
G02X1021755Y220834I-845J1001D01*
G01X1016023D01*
G03X1014825Y220618I2J-3441D01*
G03X1013884Y219512I519J-1395D01*
G01X1013839Y219284D01*
G03X1013833Y219223I311J-61D01*
G01Y219027D01*
G02X1013764Y218680I-907J0D01*
G01X1013673Y218461D01*
G02X1013094Y217966I-775J321D01*
G02X1012898Y217943I-195J816D01*
G02X1012669Y218038I0J324D01*
G01X1012204Y218503D01*
G01X1016141Y222440D02*
G03X1016964Y222781I0J1164D01*
G01X1019196Y225014D01*
G02X1019456Y225234I1446J-1446D01*
G02X1020629Y225609I1173J-1647D01*
G01X1022543D01*
G02X1023731Y225117I0J-1680D01*
G01X1012204Y226377D02*
X1012669Y225912D01*
G03X1012898Y225817I229J229D01*
G03X1013094Y225840I1J839D01*
G03X1013673Y226335I-196J816D01*
G01X1013764Y226554D01*
G03X1013833Y226901I-838J347D01*
G01Y227097D01*
G02X1013839Y227158I317J0D01*
G01X1013884Y227386D01*
G02X1014825Y228492I1460J-289D01*
G02X1016023Y228708I1200J-3225D01*
G01X1021953D01*
G03X1022600Y229017I0J832D01*
G01X1016141Y230314D02*
G03X1016964Y230655I0J1164D01*
G01X1019196Y232888D01*
G02X1019456Y233108I1446J-1446D01*
G02X1020629Y233483I1173J-1647D01*
G01X1022152D01*
G02X1022869Y233267I-1J-1300D01*
G01X1022992Y233186D01*
G03X1023198Y233147I150J228D01*
G02X1023378Y233113I49J-232D01*
G01X1012204Y234251D02*
X1012669Y233786D01*
G03X1012898Y233691I229J229D01*
G03X1013094Y233714I1J839D01*
G03X1013373Y233839I-198J815D01*
G03X1013673Y234209I-475J691D01*
G01X1013764Y234428D01*
G03X1013833Y234775I-838J347D01*
G01Y234971D01*
G02X1013839Y235032I317J0D01*
G01X1013884Y235260D01*
G02X1014825Y236366I1460J-289D01*
G02X1016024Y236582I1198J-3217D01*
G01X1021219D01*
G03X1022600Y236891I0J3241D01*
G01X1016141Y261810D02*
X1016241Y261710D01*
Y260537D01*
G02X1016029Y260025I-724J0D01*
G01X1015999Y259995D01*
G02X1015618Y259837I-381J381D01*
G01X1015240D01*
G02X1014757Y260037I0J683D01*
G02X1014554Y260527I490J490D01*
G01Y263254D01*
X1014800Y263500D01*
G01X1012204Y257873D02*
X1012304Y257773D01*
Y256600D01*
G02X1012092Y256088I-724J0D01*
G01X1012062Y256058D01*
G02X1011681Y255900I-381J381D01*
G01X1011303D01*
G02X1010820Y256100I0J683D01*
G02X1010617Y256590I490J490D01*
G01Y263417D01*
X1010800Y263600D01*
G01X1016141Y257873D02*
G02X1015424Y258170I0J1014D01*
G01X1014086Y259507D01*
G02X1013754Y260310I803J802D01*
G01Y263246D01*
X1013500Y263500D01*
G01X1012204Y253936D02*
G02X1011487Y254233I0J1014D01*
G01X1010149Y255570D01*
G02X1009817Y256373I803J802D01*
G01Y263283D01*
X1009500Y263600D01*
G54D12*
X112700Y766300D03*
X553563Y306108D03*
X921300Y74700D03*
X918100Y71900D03*
X1326250Y669550D03*
G54D22*
G01X145579Y-328699D02*
Y-346199D01*
X154313D01*
G01X167446Y-334533D02*
Y-346199D01*
G01Y-329866D02*
X167009Y-329574D01*
Y-328991D01*
X167446Y-328699D01*
X167883Y-328991D01*
Y-329574D01*
X167446Y-329866D01*
G01X181889Y-350574D02*
X183418Y-351741D01*
X185164Y-352032D01*
X186692Y-351741D01*
X188003Y-350283D01*
X188876Y-348241D01*
Y-334533D01*
G01Y-336866D02*
X188003Y-335699D01*
X186692Y-334824D01*
X185164Y-334533D01*
X183418Y-335116D01*
X182326Y-336282D01*
X181452Y-338324D01*
X181016Y-340366D01*
X181234Y-342116D01*
X182108Y-344158D01*
X183418Y-345616D01*
X185164Y-346199D01*
X186474Y-345907D01*
X188003Y-344741D01*
X188876Y-343575D01*
G01X198734Y-346199D02*
Y-328699D01*
G01Y-337157D02*
X199826Y-335699D01*
X200918Y-334824D01*
X202664Y-334533D01*
X203974Y-334824D01*
X205503Y-335991D01*
X206158Y-337741D01*
Y-346199D01*
G01X219946Y-328699D02*
Y-346199D01*
G01X216889Y-334533D02*
X223003D01*
G01X233734Y-346199D02*
Y-334533D01*
G01Y-337449D02*
X234608Y-335991D01*
X235918Y-334824D01*
X237664Y-334533D01*
X239192Y-334824D01*
X240503Y-335991D01*
X241158Y-338032D01*
Y-346199D01*
G01X254946Y-334533D02*
Y-346199D01*
G01Y-329866D02*
X254509Y-329574D01*
Y-328991D01*
X254946Y-328699D01*
X255383Y-328991D01*
Y-329574D01*
X254946Y-329866D01*
G01X268734Y-346199D02*
Y-334533D01*
G01Y-337449D02*
X269608Y-335991D01*
X270918Y-334824D01*
X272664Y-334533D01*
X274192Y-334824D01*
X275503Y-335991D01*
X276158Y-338032D01*
Y-346199D01*
G01X286889Y-350574D02*
X288418Y-351741D01*
X290164Y-352032D01*
X291692Y-351741D01*
X293003Y-350283D01*
X293876Y-348241D01*
Y-334533D01*
G01Y-336866D02*
X293003Y-335699D01*
X291692Y-334824D01*
X290164Y-334533D01*
X288418Y-335116D01*
X287326Y-336282D01*
X286452Y-338324D01*
X286016Y-340366D01*
X286234Y-342116D01*
X287108Y-344158D01*
X288418Y-345616D01*
X290164Y-346199D01*
X291474Y-345907D01*
X293003Y-344741D01*
X293876Y-343575D01*
G01X320579Y-346199D02*
Y-328699D01*
X325819D01*
X327566Y-329574D01*
X328876Y-331616D01*
X329313Y-333949D01*
X328876Y-336282D01*
X327784Y-338032D01*
X325819Y-338908D01*
X320579D01*
G01X346813Y-346199D02*
X338079D01*
Y-328699D01*
X346813D01*
G01X343319Y-337157D02*
X338079D01*
G01X361692Y-336866D02*
X362566Y-335991D01*
X363221Y-334533D01*
X363658Y-332490D01*
X363221Y-330741D01*
X362348Y-329574D01*
X360819Y-328699D01*
X354924D01*
Y-346199D01*
X362129D01*
X363658Y-345033D01*
X364531Y-343282D01*
X364968Y-341241D01*
X364531Y-339199D01*
X363221Y-337449D01*
X361692Y-336866D01*
X354924D01*
G01X390579Y-346199D02*
Y-328699D01*
X395819D01*
X397566Y-329574D01*
X398876Y-331616D01*
X399313Y-333949D01*
X398876Y-336282D01*
X397784Y-338032D01*
X395819Y-338908D01*
X390579D01*
G01X406769Y-346199D02*
Y-328699D01*
X412446Y-343282D01*
X418123Y-328699D01*
Y-346199D01*
G01X434749Y-330158D02*
X433439Y-329282D01*
X431911Y-328699D01*
X430164D01*
X428199Y-329574D01*
X426671Y-331032D01*
X425579Y-332783D01*
X424706Y-335699D01*
X424487Y-338324D01*
X424924Y-340949D01*
X425579Y-342699D01*
X426889Y-344449D01*
X428418Y-345616D01*
X429946Y-346199D01*
X431474D01*
X433003Y-345616D01*
X434313Y-344741D01*
X435405Y-343575D01*
G01X460579Y-346199D02*
Y-328699D01*
X465819D01*
X467566Y-329574D01*
X468876Y-331616D01*
X469313Y-333949D01*
X468876Y-336282D01*
X467784Y-338032D01*
X465819Y-338908D01*
X460579D01*
G01X476987Y-328699D02*
X482446Y-346199D01*
X487905Y-328699D01*
G01X499946D02*
Y-346199D01*
G01X494924Y-328699D02*
X504968D01*
G01X284269Y-301199D02*
Y-283699D01*
X289946Y-298282D01*
X295623Y-283699D01*
Y-301199D01*
G01X307446D02*
X306136Y-300907D01*
X304826Y-299741D01*
X303952Y-297699D01*
X303516Y-295366D01*
X303952Y-293032D01*
X304826Y-290991D01*
X306136Y-289824D01*
X307446Y-289533D01*
X308756Y-289824D01*
X310066Y-290991D01*
X310939Y-293032D01*
X311158Y-295366D01*
X310939Y-297699D01*
X310066Y-299741D01*
X308756Y-300907D01*
X307446Y-301199D01*
G01X328876Y-283699D02*
Y-301199D01*
G01Y-298575D02*
X328003Y-300033D01*
X326692Y-300907D01*
X325164Y-301199D01*
X323418Y-300616D01*
X322108Y-299158D01*
X321234Y-297408D01*
X321016Y-295366D01*
X321234Y-293324D01*
X322108Y-291574D01*
X323418Y-290116D01*
X325164Y-289533D01*
X326692Y-289824D01*
X327784Y-290408D01*
X328876Y-291574D01*
G01X339171Y-293324D02*
X346158D01*
X345503Y-291282D01*
X344411Y-290116D01*
X342883Y-289533D01*
X341354Y-289824D01*
X340044Y-290699D01*
X339171Y-292741D01*
X338734Y-294491D01*
Y-296241D01*
X339171Y-297991D01*
X340263Y-299741D01*
X341573Y-300907D01*
X343101Y-301199D01*
X344629Y-300616D01*
X346158Y-298866D01*
G01X359946Y-301199D02*
Y-283699D01*
G01X556346Y-346199D02*
Y-328699D01*
X553726Y-332199D01*
G01Y-346199D02*
X558966D01*
G01X569043Y-343575D02*
X570352Y-345033D01*
X571881Y-345907D01*
X573846Y-346199D01*
X575811Y-345616D01*
X577339Y-344449D01*
X578431Y-342408D01*
X578649Y-340074D01*
X578213Y-337741D01*
X577121Y-336282D01*
X575592Y-335116D01*
X574064Y-334824D01*
X572536Y-335116D01*
X570571Y-336282D01*
X571226Y-328699D01*
X577121D01*
G01X591346Y-346199D02*
Y-328699D01*
X588726Y-332199D01*
G01Y-346199D02*
X593966D01*
G01X608846Y-328699D02*
X607099Y-329282D01*
X605789Y-330741D01*
X604916Y-332490D01*
X604261Y-334824D01*
X604043Y-337449D01*
X604261Y-340074D01*
X604916Y-342408D01*
X605789Y-344158D01*
X607099Y-345616D01*
X608846Y-346199D01*
X610592Y-345616D01*
X611903Y-344158D01*
X612776Y-342408D01*
X613431Y-340074D01*
X613649Y-337449D01*
X613431Y-334824D01*
X612776Y-332490D01*
X611903Y-330741D01*
X610592Y-329282D01*
X608846Y-328699D01*
G01X621543Y-343575D02*
X622852Y-345033D01*
X624381Y-345907D01*
X626346Y-346199D01*
X628311Y-345616D01*
X629839Y-344449D01*
X630931Y-342408D01*
X631149Y-340074D01*
X630713Y-337741D01*
X629621Y-336282D01*
X628092Y-335116D01*
X626564Y-334824D01*
X625036Y-335116D01*
X623071Y-336282D01*
X623726Y-328699D01*
X629621D01*
G01X543229Y-301199D02*
Y-283699D01*
X548469D01*
X550216Y-284574D01*
X551526Y-286616D01*
X551963Y-288949D01*
X551526Y-291282D01*
X550434Y-293032D01*
X548469Y-293908D01*
X543229D01*
G01X569899Y-285158D02*
X568589Y-284282D01*
X567061Y-283699D01*
X565314D01*
X563349Y-284574D01*
X561821Y-286032D01*
X560729Y-287783D01*
X559856Y-290699D01*
X559637Y-293324D01*
X560074Y-295949D01*
X560729Y-297699D01*
X562039Y-299449D01*
X563568Y-300616D01*
X565096Y-301199D01*
X566624D01*
X568153Y-300616D01*
X569463Y-299741D01*
X570555Y-298575D01*
G01X584342Y-291866D02*
X585216Y-290991D01*
X585871Y-289533D01*
X586308Y-287490D01*
X585871Y-285741D01*
X584998Y-284574D01*
X583469Y-283699D01*
X577574D01*
Y-301199D01*
X584779D01*
X586308Y-300033D01*
X587181Y-298282D01*
X587618Y-296241D01*
X587181Y-294199D01*
X585871Y-292449D01*
X584342Y-291866D01*
X577574D01*
G01X593546Y-307032D02*
X606646D01*
G01X612574Y-301199D02*
Y-283699D01*
X622618Y-301199D01*
Y-283699D01*
G01X635096Y-301199D02*
X633349Y-300907D01*
X631821Y-299741D01*
X630511Y-297991D01*
X629637Y-295949D01*
X629201Y-293616D01*
Y-291282D01*
X629637Y-288949D01*
X630511Y-286907D01*
X631821Y-285158D01*
X633349Y-283991D01*
X635096Y-283699D01*
X636842Y-283991D01*
X638371Y-285158D01*
X639681Y-286907D01*
X640555Y-288949D01*
X640991Y-291282D01*
Y-293616D01*
X640555Y-295949D01*
X639681Y-297991D01*
X638371Y-299741D01*
X636842Y-300907D01*
X635096Y-301199D01*
G01X685937Y-283699D02*
X691396Y-301199D01*
X696855Y-283699D01*
G01X713263Y-301199D02*
X704529D01*
Y-283699D01*
X713263D01*
G01X709769Y-292157D02*
X704529D01*
G01X722029Y-301199D02*
Y-283699D01*
X727488D01*
X729234Y-284574D01*
X730326Y-285741D01*
X730763Y-288074D01*
X730326Y-290408D01*
X729016Y-291866D01*
X727488Y-292741D01*
X722029D01*
G01X727488D02*
X730763Y-301199D01*
G01X743896Y-301782D02*
X743459Y-301491D01*
Y-300907D01*
X743896Y-300616D01*
X744333Y-300907D01*
Y-301491D01*
X743896Y-301782D01*
G01X717646Y-346199D02*
Y-328699D01*
X715026Y-332199D01*
G01Y-346199D02*
X720266D01*
G01X819479Y-283699D02*
Y-301199D01*
X828213D01*
G01X845276D02*
Y-289533D01*
G01Y-291574D02*
X844403Y-290408D01*
X843092Y-289824D01*
X841564Y-289533D01*
X840036Y-290116D01*
X838726Y-291282D01*
X837852Y-293032D01*
X837416Y-295366D01*
X837852Y-297699D01*
X838726Y-299449D01*
X840036Y-300616D01*
X841564Y-301199D01*
X843092Y-300907D01*
X844403Y-300033D01*
X845276Y-298866D01*
G01X854261Y-306449D02*
X855571Y-307032D01*
X857318Y-306449D01*
X858409Y-305283D01*
X859283Y-303824D01*
X860592Y-299158D01*
X863431Y-289533D01*
G01X856444D02*
X860592Y-299158D01*
G01X873071Y-293324D02*
X880058D01*
X879403Y-291282D01*
X878311Y-290116D01*
X876783Y-289533D01*
X875254Y-289824D01*
X873944Y-290699D01*
X873071Y-292741D01*
X872634Y-294491D01*
Y-296241D01*
X873071Y-297991D01*
X874163Y-299741D01*
X875473Y-300907D01*
X877001Y-301199D01*
X878529Y-300616D01*
X880058Y-298866D01*
G01X890789Y-301199D02*
Y-289533D01*
G01Y-291866D02*
X891881Y-290699D01*
X892973Y-289824D01*
X894501Y-289533D01*
X895592Y-289824D01*
X896903Y-290699D01*
G01X871963Y-328699D02*
Y-346199D01*
X863229D01*
G01X854244Y-338908D02*
X852716Y-336866D01*
X851406Y-335699D01*
X849659Y-335116D01*
X848131Y-335699D01*
X847039Y-336866D01*
X846166Y-338616D01*
X845948Y-340657D01*
X846166Y-342408D01*
X847039Y-344158D01*
X848350Y-345616D01*
X849878Y-346199D01*
X851624Y-345616D01*
X853153Y-343866D01*
X854026Y-341241D01*
X854244Y-338324D01*
X853808Y-334533D01*
X853153Y-332490D01*
X852061Y-330449D01*
X850533Y-328991D01*
X849004Y-328699D01*
X847476Y-329282D01*
X846384Y-330741D01*
G01X959846Y-328699D02*
X962902Y-346199D01*
X966396Y-328699D01*
X969889Y-346199D01*
X972946Y-328699D01*
G01X979529Y-346199D02*
Y-328699D01*
X984769D01*
X986516Y-329574D01*
X987826Y-331616D01*
X988263Y-333949D01*
X987826Y-336282D01*
X986734Y-338032D01*
X984769Y-338908D01*
X979529D01*
G01X996811Y-346199D02*
Y-328699D01*
G01X1005981D02*
Y-346199D01*
G01Y-337449D02*
X996811D01*
G01X1016058Y-340366D02*
X1021734D01*
G01X1031593Y-346199D02*
Y-328699D01*
G01X1039889D02*
X1031593Y-339491D01*
G01X1041199Y-346199D02*
X1035304Y-334533D01*
G01X1058263Y-346199D02*
X1049529D01*
Y-328699D01*
X1058263D01*
G01X1054769Y-337157D02*
X1049529D01*
G01X1066374Y-346199D02*
Y-328699D01*
X1076418Y-346199D01*
Y-328699D01*
G01X1083874Y-346199D02*
Y-328699D01*
X1093918Y-346199D01*
Y-328699D01*
G01X961593Y-301199D02*
Y-283699D01*
X965959D01*
X967706Y-284574D01*
X969016Y-285741D01*
X970108Y-287490D01*
X970981Y-289533D01*
X971199Y-292449D01*
X970981Y-295366D01*
X970108Y-297408D01*
X969016Y-299158D01*
X967706Y-300324D01*
X965959Y-301199D01*
X961593D01*
G01X980621Y-293324D02*
X987608D01*
X986953Y-291282D01*
X985861Y-290116D01*
X984333Y-289533D01*
X982804Y-289824D01*
X981494Y-290699D01*
X980621Y-292741D01*
X980184Y-294491D01*
Y-296241D01*
X980621Y-297991D01*
X981713Y-299741D01*
X983023Y-300907D01*
X984551Y-301199D01*
X986079Y-300616D01*
X987608Y-298866D01*
G01X998121Y-299158D02*
X999213Y-300324D01*
X1000741Y-301199D01*
X1002051D01*
X1003361Y-300616D01*
X1004234Y-299741D01*
X1004671Y-298575D01*
X1004453Y-296824D01*
X1003579Y-295949D01*
X999649Y-294199D01*
X998776Y-292157D01*
X999213Y-290699D01*
X1000086Y-289824D01*
X1001396Y-289533D01*
X1002706Y-289824D01*
X1004016Y-290699D01*
G01X1018896Y-289533D02*
Y-301199D01*
G01Y-284866D02*
X1018459Y-284574D01*
Y-283991D01*
X1018896Y-283699D01*
X1019333Y-283991D01*
Y-284574D01*
X1018896Y-284866D01*
G01X1033339Y-305574D02*
X1034868Y-306741D01*
X1036614Y-307032D01*
X1038142Y-306741D01*
X1039453Y-305283D01*
X1040326Y-303241D01*
Y-289533D01*
G01Y-291866D02*
X1039453Y-290699D01*
X1038142Y-289824D01*
X1036614Y-289533D01*
X1034868Y-290116D01*
X1033776Y-291282D01*
X1032902Y-293324D01*
X1032466Y-295366D01*
X1032684Y-297116D01*
X1033558Y-299158D01*
X1034868Y-300616D01*
X1036614Y-301199D01*
X1037924Y-300907D01*
X1039453Y-299741D01*
X1040326Y-298575D01*
G01X1050184Y-301199D02*
Y-289533D01*
G01Y-292449D02*
X1051058Y-290991D01*
X1052368Y-289824D01*
X1054114Y-289533D01*
X1055642Y-289824D01*
X1056953Y-290991D01*
X1057608Y-293032D01*
Y-301199D01*
G01X1068121Y-293324D02*
X1075108D01*
X1074453Y-291282D01*
X1073361Y-290116D01*
X1071833Y-289533D01*
X1070304Y-289824D01*
X1068994Y-290699D01*
X1068121Y-292741D01*
X1067684Y-294491D01*
Y-296241D01*
X1068121Y-297991D01*
X1069213Y-299741D01*
X1070523Y-300907D01*
X1072051Y-301199D01*
X1073579Y-300616D01*
X1075108Y-298866D01*
G01X1085839Y-301199D02*
Y-289533D01*
G01Y-291866D02*
X1086931Y-290699D01*
X1088023Y-289824D01*
X1089551Y-289533D01*
X1090642Y-289824D01*
X1091953Y-290699D01*
G01X1132596Y-346199D02*
Y-328699D01*
X1129976Y-332199D01*
G01Y-346199D02*
X1135216D01*
G01X1150096D02*
Y-328699D01*
X1147476Y-332199D01*
G01Y-346199D02*
X1152716D01*
G01X1163666Y-346782D02*
X1171526Y-328699D01*
G01X1185096Y-346199D02*
Y-328699D01*
X1182476Y-332199D01*
G01Y-346199D02*
X1187716D01*
G01X1198448Y-338908D02*
X1199976Y-336866D01*
X1201286Y-335699D01*
X1203033Y-335116D01*
X1204561Y-335699D01*
X1205653Y-336866D01*
X1206526Y-338616D01*
X1206744Y-340657D01*
X1206526Y-342408D01*
X1205653Y-344158D01*
X1204342Y-345616D01*
X1202814Y-346199D01*
X1201068Y-345616D01*
X1199539Y-343866D01*
X1198666Y-341241D01*
X1198448Y-338324D01*
X1198884Y-334533D01*
X1199539Y-332490D01*
X1200631Y-330449D01*
X1202159Y-328991D01*
X1203688Y-328699D01*
X1205216Y-329282D01*
X1206308Y-330741D01*
G01X1216166Y-346782D02*
X1224026Y-328699D01*
G01X1233448Y-331616D02*
X1234758Y-329866D01*
X1236286Y-328991D01*
X1238033Y-328699D01*
X1240216Y-329282D01*
X1241744Y-330741D01*
X1242181Y-332490D01*
X1241963Y-334241D01*
X1241089Y-335699D01*
X1236723Y-338616D01*
X1234758Y-340657D01*
X1233448Y-343575D01*
X1233011Y-346199D01*
X1242181D01*
G01X1255096Y-328699D02*
X1253349Y-329282D01*
X1252039Y-330741D01*
X1251166Y-332490D01*
X1250511Y-334824D01*
X1250293Y-337449D01*
X1250511Y-340074D01*
X1251166Y-342408D01*
X1252039Y-344158D01*
X1253349Y-345616D01*
X1255096Y-346199D01*
X1256842Y-345616D01*
X1258153Y-344158D01*
X1259026Y-342408D01*
X1259681Y-340074D01*
X1259899Y-337449D01*
X1259681Y-334824D01*
X1259026Y-332490D01*
X1258153Y-330741D01*
X1256842Y-329282D01*
X1255096Y-328699D01*
G01X1272596Y-346199D02*
Y-328699D01*
X1269976Y-332199D01*
G01Y-346199D02*
X1275216D01*
G01X1285948Y-338908D02*
X1287476Y-336866D01*
X1288786Y-335699D01*
X1290533Y-335116D01*
X1292061Y-335699D01*
X1293153Y-336866D01*
X1294026Y-338616D01*
X1294244Y-340657D01*
X1294026Y-342408D01*
X1293153Y-344158D01*
X1291842Y-345616D01*
X1290314Y-346199D01*
X1288568Y-345616D01*
X1287039Y-343866D01*
X1286166Y-341241D01*
X1285948Y-338324D01*
X1286384Y-334533D01*
X1287039Y-332490D01*
X1288131Y-330449D01*
X1289659Y-328991D01*
X1291188Y-328699D01*
X1292716Y-329282D01*
X1293808Y-330741D01*
G01X1180293Y-301199D02*
Y-283699D01*
X1184659D01*
X1186406Y-284574D01*
X1187716Y-285741D01*
X1188808Y-287490D01*
X1189681Y-289533D01*
X1189899Y-292449D01*
X1189681Y-295366D01*
X1188808Y-297408D01*
X1187716Y-299158D01*
X1186406Y-300324D01*
X1184659Y-301199D01*
X1180293D01*
G01X1206526D02*
Y-289533D01*
G01Y-291574D02*
X1205653Y-290408D01*
X1204342Y-289824D01*
X1202814Y-289533D01*
X1201286Y-290116D01*
X1199976Y-291282D01*
X1199102Y-293032D01*
X1198666Y-295366D01*
X1199102Y-297699D01*
X1199976Y-299449D01*
X1201286Y-300616D01*
X1202814Y-301199D01*
X1204342Y-300907D01*
X1205653Y-300033D01*
X1206526Y-298866D01*
G01X1220096Y-283699D02*
Y-301199D01*
G01X1217039Y-289533D02*
X1223153D01*
G01X1234321Y-293324D02*
X1241308D01*
X1240653Y-291282D01*
X1239561Y-290116D01*
X1238033Y-289533D01*
X1236504Y-289824D01*
X1235194Y-290699D01*
X1234321Y-292741D01*
X1233884Y-294491D01*
Y-296241D01*
X1234321Y-297991D01*
X1235413Y-299741D01*
X1236723Y-300907D01*
X1238251Y-301199D01*
X1239779Y-300616D01*
X1241308Y-298866D01*
G01X997007Y49560D02*
Y49939D01*
X997592Y50524D01*
Y55408D01*
X984459Y68541D01*
Y102999D01*
X982974Y104484D01*
Y115674D01*
X985400Y118100D01*
G01X1008508Y47704D02*
X985659Y70553D01*
Y103214D01*
X984174Y104699D01*
Y115074D01*
X986000Y116900D01*
G54D13*
X488462Y190761D03*
G54D23*
G01X26600Y249217D02*
X25372Y250445D01*
X22577D01*
X20906Y252116D01*
Y298873D01*
X15500Y304279D01*
Y370129D01*
X27200Y381829D01*
Y471700D01*
X32831Y477331D01*
X40318D01*
X41348Y476299D01*
X41624Y475939D01*
X41652Y475904D01*
X42471D01*
X45213Y478019D01*
X47910D01*
X49812Y479921D01*
G01X26600Y253582D02*
X25463Y252445D01*
X23406D01*
X22906Y252945D01*
Y299702D01*
X17500Y305108D01*
Y369300D01*
X29200Y381000D01*
Y470871D01*
X33660Y475331D01*
X39487D01*
X39839Y474978D01*
X40063Y474686D01*
X39975Y473986D01*
X33900Y469300D01*
G01X25350Y389000D02*
X25400D01*
X25200Y389200D01*
Y438335D01*
X20700Y442835D01*
Y708150D01*
X25200Y712650D01*
G01X23720Y472640D02*
X22500Y473860D01*
Y657500D01*
X24000Y659000D01*
G01X46087Y455819D02*
X44650Y457256D01*
Y461067D01*
X47383Y463800D01*
X48359D01*
X50279Y465720D01*
Y475412D01*
X51541Y476674D01*
Y479033D01*
X51662Y479154D01*
Y480688D01*
X50279Y482071D01*
Y487421D01*
X24800Y512900D01*
Y540900D01*
G01X89500Y466600D02*
X86300Y469800D01*
Y473748D01*
X87598Y475046D01*
Y476580D01*
X86300Y477878D01*
Y478917D01*
X73053Y492164D01*
X60982D01*
X27450Y525696D01*
Y669850D01*
X26100Y671200D01*
G01X122600Y471500D02*
X109900D01*
X88500Y492900D01*
X78245D01*
X76665Y494480D01*
X65119D01*
X62383Y497216D01*
X58312D01*
X31150Y524378D01*
Y658211D01*
X29500Y659861D01*
Y676500D01*
G01X21300Y728400D02*
Y728447D01*
X22714Y729861D01*
X38884D01*
X60027Y708718D01*
X80565D01*
X83938Y712091D01*
X93435D01*
X101583Y720239D01*
Y728569D01*
X99481Y730671D01*
X96329D01*
X95400Y731600D01*
G01X21108Y732713D02*
X21960Y731861D01*
X39713D01*
X60856Y710718D01*
X79736D01*
X83109Y714091D01*
X92606D01*
X99583Y721068D01*
Y727740D01*
X98652Y728671D01*
X95871D01*
X95400Y728200D01*
G01X35300Y303100D02*
Y304000D01*
X41300Y310000D01*
Y316683D01*
X41450Y316833D01*
Y318367D01*
X41300Y318517D01*
Y323300D01*
X48485Y330485D01*
Y341386D01*
X51559Y344460D01*
Y349395D01*
X52521Y350357D01*
G01X131004Y422710D02*
X99394Y391100D01*
X75384D01*
X61400Y377116D01*
Y348574D01*
X56250Y343424D01*
Y331050D01*
X56450Y330850D01*
Y324433D01*
X51817Y319800D01*
X51011D01*
X48700Y317489D01*
Y311117D01*
X49650Y310167D01*
Y308633D01*
X42358Y301341D01*
X42241D01*
X40400Y299500D01*
X39000D01*
G01X53100Y279500D02*
X52000Y280600D01*
Y311760D01*
X50200Y313560D01*
Y316867D01*
X51633Y318300D01*
X55800D01*
X72651Y335151D01*
Y344809D01*
X63500Y353960D01*
G01X120200Y436400D02*
Y433940D01*
X109392Y423132D01*
Y420969D01*
X104756Y416333D01*
X102593D01*
X89660Y403400D01*
X70985D01*
X56787Y389202D01*
Y358035D01*
X59593Y355229D01*
Y348889D01*
X52150Y341446D01*
Y325850D01*
X47200Y320900D01*
Y310000D01*
X47800Y309400D01*
G01X58700Y308600D02*
Y307383D01*
X64583Y301500D01*
X70517D01*
X76767Y295250D01*
X78889D01*
X80850Y293289D01*
Y287900D01*
X81450Y287300D01*
Y281778D01*
X79400Y279728D01*
Y265822D01*
X80350Y264872D01*
Y257716D01*
X80877Y257189D01*
Y249110D01*
X108793Y221194D01*
Y216257D01*
X111967Y213083D01*
Y199632D01*
G01X52050Y316100D02*
X53900Y314250D01*
Y310061D01*
X64661Y299300D01*
X67483D01*
X71183Y295600D01*
X74295D01*
X76145Y293750D01*
X78267D01*
X79350Y292667D01*
Y287278D01*
X79950Y286678D01*
Y282400D01*
X77600Y280050D01*
Y274917D01*
X77650Y274867D01*
Y273333D01*
X77600Y273283D01*
Y265500D01*
X78850Y264250D01*
Y257094D01*
X79377Y256567D01*
Y248488D01*
X103100Y224765D01*
Y211600D01*
G01X38518Y376916D02*
X37450Y377984D01*
Y419287D01*
X42400Y424237D01*
Y465801D01*
X45327Y468728D01*
X45912Y468878D01*
X46396Y469002D01*
X47004Y468642D01*
X47734Y465792D01*
G01X34153Y376916D02*
X35450Y378213D01*
Y420116D01*
X40400Y425066D01*
Y466630D01*
X43192Y469423D01*
X44586Y470816D01*
X45416D01*
X45900Y470940D01*
X46262Y471548D01*
X45531Y474400D01*
G01X54200Y347400D02*
X55982D01*
X58093Y349511D01*
Y354607D01*
X49900Y362800D01*
Y456700D01*
X46500Y460100D01*
Y460300D01*
G01X126122Y432323D02*
X120571Y426772D01*
Y416539D01*
X109646Y405614D01*
X100713D01*
X88599Y393500D01*
X63946D01*
X62838Y392392D01*
G01X122700Y476100D02*
X122501Y476299D01*
X112601D01*
X84550Y504350D01*
X68191D01*
X65811Y501970D01*
X57802D01*
X34150Y525622D01*
Y659455D01*
X32650Y660955D01*
Y670062D01*
X35766Y673178D01*
G01X34500Y666500D02*
Y661227D01*
X35650Y660077D01*
Y526244D01*
X58424Y503470D01*
X65123D01*
X68154Y506501D01*
X71401D01*
X73218Y508318D01*
X87382D01*
X117300Y478400D01*
X122700D01*
G01X127973Y488524D02*
X126422Y486973D01*
X117331D01*
X92204Y512100D01*
X91003Y513300D01*
X70639D01*
X69131Y511792D01*
X56468D01*
X40150Y528110D01*
Y670368D01*
X39900Y670618D01*
Y678100D01*
G01X131122Y488524D02*
X129523Y486925D01*
Y484731D01*
X128616Y483824D01*
X118358D01*
X91357Y510825D01*
X90381Y511800D01*
X71261D01*
X69753Y510292D01*
X55846D01*
X38650Y527488D01*
Y669746D01*
X38000Y670396D01*
Y684000D01*
G01X33600Y675800D02*
Y673700D01*
X31150Y671250D01*
Y660333D01*
X32650Y658833D01*
Y525000D01*
X58551Y499099D01*
X63718D01*
X65634Y497183D01*
X87037D01*
X110420Y473800D01*
X122600D01*
G01X131122Y485374D02*
X130423Y484675D01*
Y484358D01*
X128989Y482924D01*
X117136D01*
X89759Y510300D01*
X71883D01*
X70375Y508792D01*
X55224D01*
X37150Y526866D01*
Y660699D01*
X36624Y661225D01*
Y669155D01*
G01X61870Y515670D02*
X59288Y518252D01*
X54252D01*
X43500Y529004D01*
Y665600D01*
X43600Y665700D01*
G01X121673Y497973D02*
X119478D01*
X96951Y520500D01*
X90017D01*
X89967Y520550D01*
X88433D01*
X88383Y520500D01*
X76600D01*
X75289Y521811D01*
X71711D01*
X65283Y528239D01*
X60639D01*
X50000Y538878D01*
Y680900D01*
X45800Y685100D01*
G01X60300Y533900D02*
X54100Y540100D01*
Y643483D01*
X54850Y644233D01*
Y645767D01*
X54100Y646517D01*
Y666700D01*
X54200Y666800D01*
G01X42100Y684000D02*
X45450Y680650D01*
Y541306D01*
X60656Y526100D01*
X65300D01*
X74700Y516700D01*
X95658D01*
X96759Y515600D01*
X117537Y494822D01*
X121673D01*
G01X134272Y491674D02*
X132720Y490122D01*
X117246D01*
X92568Y514800D01*
X70017D01*
X68509Y513292D01*
X57090D01*
X41750Y528632D01*
Y669550D01*
X43100Y670900D01*
G01X121673Y504272D02*
X101145Y524800D01*
X72600D01*
X67000Y530400D01*
X60600D01*
X52600Y538400D01*
Y644600D01*
X53000Y645000D01*
G01X97480Y266420D02*
X108986Y254914D01*
X110185D01*
X117271Y262000D01*
X122272D01*
X155972Y295700D01*
X166518D01*
X167700Y296882D01*
G01X82500Y362890D02*
Y357000D01*
X104522Y334978D01*
Y276731D01*
X107340Y273913D01*
Y266140D01*
G01X167600Y247600D02*
Y253721D01*
X172550Y258671D01*
Y298891D01*
X169709Y301732D01*
X163058D01*
X143890Y320900D01*
X133300D01*
X113195Y341000D01*
X108382D01*
X97278Y352104D01*
Y370578D01*
X133154Y406454D01*
Y433726D01*
X127670Y439210D01*
Y449427D01*
X127820Y449577D01*
Y452280D01*
G01X72708Y382055D02*
X79153Y388500D01*
X100949D01*
X131304Y418855D01*
G01X73900Y527050D02*
X71300Y529650D01*
Y537771D01*
X71420Y537891D01*
Y539425D01*
X71300Y539545D01*
Y541183D01*
X71850Y541733D01*
Y543267D01*
X70217Y544900D01*
X69200D01*
X65381Y548719D01*
G01X127973Y491674D02*
X127916D01*
X126421Y493169D01*
Y505179D01*
X125310Y506290D01*
X122130D01*
X110160Y518260D01*
Y528620D01*
X88680Y550100D01*
Y556613D01*
X87608Y557685D01*
G01X111300Y756000D02*
X97600Y742300D01*
Y736417D01*
X81283Y720100D01*
X77400D01*
X74500Y717200D01*
Y713400D01*
G01X93100Y813200D02*
Y807400D01*
X95900Y804600D01*
Y737600D01*
X85800Y727500D01*
G01X93300Y818900D02*
X91250Y816850D01*
Y806728D01*
X94250Y803728D01*
Y738284D01*
X86966Y731000D01*
X85800D01*
G01X119800Y234531D02*
X111600Y242731D01*
Y253500D01*
X118100Y260000D01*
X123101D01*
X156801Y293700D01*
X166517D01*
X167700Y292517D01*
G01X100277Y336077D02*
X99000Y334800D01*
Y286417D01*
X97800Y285217D01*
Y272474D01*
X101463Y268811D01*
G01X122000Y343300D02*
Y349198D01*
X144601Y371799D01*
X156573D01*
G01X102000Y364700D02*
X113150Y353550D01*
X124230D01*
X143979Y373299D01*
Y376965D01*
X154883Y387869D01*
X161210D01*
X171434Y398093D01*
G01X117300Y361700D02*
X122200D01*
X136240Y375740D01*
Y410313D01*
X170750Y444823D01*
Y461051D01*
X190957Y481258D01*
Y560764D01*
X193001Y562808D01*
Y574708D01*
G01X137862Y361723D02*
Y344293D01*
X146848Y335307D01*
Y326248D01*
X152544Y320552D01*
X161603D01*
X175566Y306589D01*
Y268131D01*
X196197Y247500D01*
X206200D01*
G01X183400Y221600D02*
X211956Y250156D01*
Y260694D01*
X200310Y272340D01*
Y291746D01*
X191500Y300556D01*
Y300557D01*
X182900Y309157D01*
Y309158D01*
X180266Y311792D01*
X180265D01*
X178801Y313256D01*
X178800D01*
X172882Y319174D01*
Y332338D01*
X161311Y343909D01*
Y371428D01*
G01X141216Y361163D02*
Y349012D01*
X149349Y340879D01*
Y327283D01*
X153580Y323052D01*
X162639D01*
X178066Y307625D01*
Y270418D01*
X182885Y265599D01*
X192014D01*
X193303Y264310D01*
G01X209200Y252800D02*
X189500Y272500D01*
Y299727D01*
X154041Y335186D01*
Y339723D01*
X145027Y348737D01*
Y361163D01*
G01X150269Y598347D02*
X149618Y597696D01*
Y585918D01*
X148900Y585200D01*
X146918D01*
X146275Y584557D01*
Y583657D01*
X146775Y583157D01*
X152075D01*
X152575Y582657D01*
Y581657D01*
X152075Y581157D01*
X146775D01*
X146275Y580657D01*
Y564340D01*
X146775Y563840D01*
X148200D01*
X148700Y563340D01*
Y560000D01*
X148875Y559825D01*
Y559749D01*
X150439Y558185D01*
Y551895D01*
X151644Y550690D01*
Y541294D01*
X153188Y539750D01*
Y538899D01*
G01X156566Y614095D02*
X158116Y615645D01*
X165630D01*
X176780Y604495D01*
Y547737D01*
X169509Y540466D01*
X168273D01*
X167316Y539509D01*
Y538273D01*
X164809Y535766D01*
X162617D01*
G01X143968Y601495D02*
Y604800D01*
X143468Y605300D01*
X139768D01*
X139268Y604800D01*
Y599897D01*
X139768Y599397D01*
X142000D01*
X142500Y598897D01*
Y597897D01*
X142000Y597397D01*
X139768D01*
X139268Y596897D01*
Y595897D01*
X139768Y595397D01*
X141000D01*
X141500Y594897D01*
Y593897D01*
X141000Y593397D01*
X136697D01*
X136000Y592700D01*
Y590722D01*
X136500Y590222D01*
X137901D01*
X138401Y589722D01*
Y588722D01*
X137901Y588222D01*
X136500D01*
X136000Y587722D01*
Y586722D01*
X136500Y586222D01*
X137901D01*
X138401Y585722D01*
Y584722D01*
X137901Y584222D01*
X136500D01*
X136000Y583722D01*
Y582722D01*
X136500Y582222D01*
X137901D01*
X138401Y581722D01*
Y548274D01*
X142081Y544594D01*
Y541482D01*
X143043Y540520D01*
X145303D01*
X146869Y538954D01*
G01X140821Y614106D02*
X139219Y612504D01*
X137035D01*
X136071Y611540D01*
Y609629D01*
X136500Y609200D01*
X141400D01*
X141900Y608700D01*
Y607000D01*
X141400Y606500D01*
X136671D01*
X136071Y605900D01*
Y594553D01*
X134721Y593203D01*
Y581879D01*
X136901Y579699D01*
Y547174D01*
X140209Y543866D01*
Y540269D01*
X144736Y535742D01*
X146858D01*
G01X159716Y610945D02*
X161661Y609000D01*
X163700D01*
X170780Y601920D01*
Y554431D01*
X159449Y543100D01*
Y542048D01*
G01X159716Y614095D02*
X161316Y612495D01*
X163508D01*
X164415Y611588D01*
Y610352D01*
X172280Y602487D01*
Y550580D01*
X168900Y547200D01*
X165558D01*
X161067Y542709D01*
Y534774D01*
X160593Y534300D01*
X159923D01*
X159449Y534774D01*
Y538898D01*
G01X159716Y595197D02*
X163030Y591883D01*
Y560975D01*
X162005Y559950D01*
X160637D01*
X159730Y559043D01*
Y552579D01*
X157899Y550748D01*
Y528844D01*
X158824Y527919D01*
X168800D01*
X169300Y528419D01*
Y533600D01*
X168900Y534000D01*
X164700D01*
X164300Y533600D01*
Y531400D01*
X163800Y530900D01*
X161198D01*
X159456Y532642D01*
G01X166016Y610944D02*
X173780Y603180D01*
Y549780D01*
X169124Y545124D01*
X165675D01*
X162617Y542066D01*
G01X162867Y614095D02*
X165058D01*
X175280Y603873D01*
Y548680D01*
X170216Y543616D01*
X168116D01*
X167316Y542816D01*
Y541423D01*
X166409Y540516D01*
X164217D01*
X162617Y538916D01*
G01X147115Y598360D02*
X148133D01*
X148693Y597800D01*
Y593463D01*
X148193Y592963D01*
X147200D01*
X146700Y592463D01*
Y591463D01*
X147200Y590963D01*
X148193D01*
X148693Y590463D01*
Y588875D01*
X144451Y584633D01*
Y562340D01*
X144951Y561840D01*
X146700D01*
X147200Y561340D01*
Y560340D01*
X146700Y559840D01*
X144951D01*
X144501Y559390D01*
Y558340D01*
X145001Y557840D01*
X145200D01*
X145700Y557340D01*
Y556340D01*
X145200Y555840D01*
X145001D01*
X144501Y555340D01*
Y554340D01*
X145001Y553840D01*
X145200D01*
X145700Y553340D01*
Y552340D01*
X145200Y551840D01*
X145001D01*
X144501Y551340D01*
Y548299D01*
X148900Y543900D01*
X149944D01*
X150744Y544700D01*
Y545985D01*
X150244Y546485D01*
X149400D01*
X148900Y546985D01*
Y547985D01*
X149400Y548485D01*
X150244D01*
X150744Y548985D01*
Y550317D01*
X149539Y551522D01*
Y557500D01*
X149039Y558000D01*
X147951D01*
X147451Y557500D01*
Y556436D01*
G01X147141Y614096D02*
Y620300D01*
X146641Y620800D01*
X142918D01*
X142418Y620300D01*
Y613452D01*
X142417Y613451D01*
Y610283D01*
X145567Y607133D01*
Y600901D01*
X144183Y599517D01*
Y594456D01*
X142418Y592691D01*
Y591118D01*
X139901Y588601D01*
Y548997D01*
X149981Y538917D01*
G01X150251Y617226D02*
X151832Y615645D01*
Y613487D01*
X152824Y612495D01*
X157209D01*
X158116Y611588D01*
Y609584D01*
X158800Y608900D01*
X160200D01*
X160700Y608400D01*
Y606695D01*
X160200Y606195D01*
X157495D01*
X156629Y605329D01*
Y591000D01*
X160030Y587599D01*
Y569647D01*
X156629Y566246D01*
Y552899D01*
X154744Y551014D01*
Y537379D01*
X153132Y535767D01*
G01X143968Y588898D02*
X141401Y586331D01*
Y549690D01*
X151531Y539560D01*
Y537317D01*
X149985Y535771D01*
G01X153417Y610945D02*
X155129Y609233D01*
Y590500D01*
X158530Y587099D01*
Y570269D01*
X155129Y566868D01*
Y553229D01*
X153194Y551294D01*
Y542078D01*
G01X159716Y604645D02*
X158166Y603095D01*
Y591405D01*
X158635Y590935D01*
X161530Y588040D01*
Y569025D01*
X158166Y565661D01*
Y552766D01*
X156300Y550900D01*
Y530408D01*
X153811Y527919D01*
X152525D01*
X151618Y528826D01*
Y531067D01*
X153187Y532636D01*
G01X166016Y601496D02*
X169280Y598232D01*
Y555480D01*
X162056Y548256D01*
X159537D01*
G01X150268Y601496D02*
X148682Y599910D01*
X146472D01*
X145565Y599003D01*
Y587865D01*
X142951Y585251D01*
Y555636D01*
G01X166015Y598345D02*
X167780Y596580D01*
Y558107D01*
X161029Y551356D01*
X160700D01*
G01X162100Y677800D02*
X183650Y656250D01*
Y566933D01*
X184189Y566394D01*
Y564504D01*
G01X164400Y668300D02*
X178942Y653758D01*
Y543642D01*
X178365Y543065D01*
Y535768D01*
G01X177500Y454300D02*
Y461958D01*
X192457Y476915D01*
Y560142D01*
X194501Y562186D01*
Y571213D01*
X195450Y572162D01*
Y662050D01*
X164500Y693000D01*
Y693500D01*
G01X227700Y476537D02*
X228937Y475300D01*
X232400D01*
X235600Y478500D01*
Y485270D01*
X228903Y491967D01*
Y507897D01*
X224318Y512482D01*
Y535517D01*
X227600Y538799D01*
Y545971D01*
X225700Y547871D01*
Y578200D01*
X221600Y582300D01*
Y672899D01*
X213150Y681349D01*
Y708150D01*
X219200Y714200D01*
Y737971D01*
X206171Y751000D01*
X197701D01*
X174401Y727700D01*
X159622D01*
X154022Y722100D01*
X139978D01*
X138000Y724078D01*
Y728360D01*
X140290Y730650D01*
X143450D01*
X144400Y731600D01*
G01X227700Y472200D02*
Y472800D01*
X228200Y473300D01*
X233229D01*
X237600Y477671D01*
Y486099D01*
X230903Y492796D01*
Y508726D01*
X226318Y513311D01*
Y534688D01*
X229600Y537970D01*
Y546800D01*
X227700Y548700D01*
Y579029D01*
X223600Y583129D01*
Y673728D01*
X215150Y682178D01*
Y707321D01*
X221200Y713371D01*
Y738800D01*
X207000Y753000D01*
X196872D01*
X173572Y729700D01*
X158793D01*
X153193Y724100D01*
X140807D01*
X140000Y724907D01*
Y727531D01*
X140669Y728200D01*
X144400D01*
G01X246300Y485400D02*
X245343D01*
X245089Y485654D01*
X243102D01*
X238900Y489856D01*
Y494900D01*
X235400Y498400D01*
Y512491D01*
X242200Y519291D01*
Y573880D01*
X230549Y585531D01*
Y674175D01*
X224500Y680224D01*
Y744102D01*
X197402Y771200D01*
X174771D01*
X171255Y774716D01*
X164197D01*
X162900Y773419D01*
Y771900D01*
X163800Y771000D01*
G01X246407Y488799D02*
X245262Y487654D01*
X243931D01*
X240900Y490685D01*
Y495729D01*
X237400Y499229D01*
Y511662D01*
X244201Y518463D01*
Y520119D01*
X244200Y520120D01*
Y574709D01*
X232549Y586360D01*
Y675004D01*
X226500Y681053D01*
Y744931D01*
X198231Y773200D01*
X175600D01*
X172084Y776716D01*
X163368D01*
X160900Y774248D01*
Y771500D01*
X160400Y771000D01*
G01X174943Y321015D02*
Y325336D01*
X179920Y330313D01*
Y354260D01*
X181800Y356140D01*
Y436059D01*
X195568Y449827D01*
Y461265D01*
X196239Y461936D01*
Y462262D01*
G01X283622Y226340D02*
X282140Y227822D01*
Y229629D01*
X277569Y234200D01*
X263900D01*
X221500Y276600D01*
Y295976D01*
X211600Y305876D01*
Y315831D01*
X203400Y324031D01*
Y351300D01*
X188400Y366300D01*
Y412300D01*
X191200Y415100D01*
X200100D01*
G01X279257Y226340D02*
X280140Y227223D01*
Y228800D01*
X276740Y232200D01*
X263071D01*
X219500Y275771D01*
Y295147D01*
X209600Y305047D01*
Y315002D01*
X201400Y323202D01*
Y350471D01*
X186400Y365471D01*
Y413129D01*
X188501Y415230D01*
Y416399D01*
X185000Y419900D01*
G01X1062044Y-4173D02*
X1060412Y-2541D01*
X1049600D01*
X1049519Y-2622D01*
X1042181D01*
X1042100Y-2541D01*
X1020753D01*
X1014992Y-8302D01*
X973263D01*
X966630Y-14935D01*
X504734D01*
X415548Y74251D01*
Y150546D01*
X407485Y158609D01*
X407486Y160973D01*
Y184751D01*
X362337Y229900D01*
X285358D01*
X245232Y270026D01*
Y284299D01*
X231140Y298391D01*
Y356114D01*
X192000Y395254D01*
Y402929D01*
X193300Y404229D01*
Y405279D01*
X192150Y406429D01*
G01X1065620Y-4335D02*
Y-3695D01*
X1062466Y-541D01*
X1048771D01*
X1048690Y-622D01*
X1043010D01*
X1042929Y-541D01*
X1019924D01*
X1014163Y-6302D01*
X972434D01*
X965801Y-12935D01*
X505563D01*
X417548Y75080D01*
Y151375D01*
X409486Y159437D01*
Y185580D01*
X363166Y231900D01*
X286187D01*
X247232Y270855D01*
Y285128D01*
X233140Y299220D01*
Y356943D01*
X194000Y396083D01*
Y402100D01*
X195900Y404000D01*
X197000D01*
G01X197531Y451187D02*
X198600Y450118D01*
Y444071D01*
X199750Y442921D01*
Y420122D01*
X220200Y399672D01*
Y379182D01*
X219018Y378000D01*
G01X189381Y451394D02*
X189534D01*
X190534Y452394D01*
Y472824D01*
X194448Y476738D01*
Y558032D01*
X200502Y564086D01*
Y659544D01*
X174485Y685561D01*
Y718515D01*
X173000Y720000D01*
X170900D01*
X170100Y719200D01*
Y716800D01*
X171000Y715900D01*
G01X193718Y451394D02*
X192534Y452578D01*
Y471995D01*
X196448Y475909D01*
Y557203D01*
X202502Y563257D01*
Y660373D01*
X176485Y686390D01*
Y719344D01*
X173829Y722000D01*
X170071D01*
X168100Y720029D01*
Y716400D01*
X167600Y715900D01*
G01X175215Y532618D02*
X176765Y534168D01*
X178958D01*
X187650Y542860D01*
Y568606D01*
X189371Y570327D01*
Y656751D01*
X172300Y673822D01*
Y677300D01*
X171300Y678300D01*
G01X175200Y678500D02*
X174300Y677600D01*
Y673944D01*
X191151Y657093D01*
Y568666D01*
X191350Y568467D01*
Y566933D01*
X189456Y565039D01*
Y558899D01*
X189656Y558699D01*
Y541716D01*
X179008Y531068D01*
X173615D01*
X172065Y532618D01*
G01X185500Y567700D02*
Y568578D01*
X187871Y570949D01*
Y656129D01*
X167000Y677000D01*
Y686500D01*
G01X189000Y684500D02*
X195000Y678500D01*
X199500D01*
X210466Y667534D01*
Y666056D01*
X210592Y665930D01*
Y657368D01*
X210591Y656125D01*
Y654275D01*
X210592Y653032D01*
Y556270D01*
X210466Y556144D01*
Y549649D01*
X207467Y546650D01*
X205450D01*
X203300Y544500D01*
G01X205700Y559763D02*
Y651386D01*
X204570Y652516D01*
Y662430D01*
X185000Y682000D01*
Y684500D01*
G01X216404Y469751D02*
X214653Y468000D01*
X213900D01*
X212125Y469775D01*
Y546357D01*
X214240Y548472D01*
Y670522D01*
X197350Y687412D01*
Y741067D01*
X199133Y742850D01*
X200763D01*
X202719Y744806D01*
Y746919D01*
X203300Y747500D01*
G01X216282Y463288D02*
X216283D01*
Y464617D01*
X214900Y466000D01*
X213071D01*
X210125Y468946D01*
Y547186D01*
X212240Y549301D01*
Y669693D01*
X195350Y686583D01*
Y741896D01*
X198304Y744850D01*
X199934D01*
X200719Y745635D01*
Y746681D01*
X199900Y747500D01*
G01X264443Y109587D02*
X262002Y107146D01*
X227904D01*
X227273Y106515D01*
X224537D01*
X221418Y109634D01*
G01X233500Y137000D02*
X227730Y131230D01*
X226280D01*
X225650Y130600D01*
X221600D01*
X220300Y129300D01*
G01X228708Y127115D02*
X219868D01*
X215136Y131847D01*
Y142786D01*
G01X258068Y110180D02*
X257499Y109611D01*
X228814D01*
X222575Y115850D01*
Y117327D01*
X218299Y121603D01*
Y123319D01*
G01X224576Y116678D02*
X226478Y118580D01*
X259331D01*
G01X217000Y360000D02*
Y355717D01*
X226640Y346077D01*
Y296400D01*
X233300Y289740D01*
Y269001D01*
X249871Y252430D01*
Y252429D01*
X265400Y236900D01*
X271100D01*
X271231Y237031D01*
G01X266500Y239400D02*
X266436D01*
X252371Y253465D01*
Y253466D01*
X235800Y270037D01*
Y290776D01*
X229140Y297436D01*
Y347410D01*
X219580Y356970D01*
G01X214776Y352807D02*
X216373D01*
X224140Y345040D01*
Y289660D01*
X230400Y283400D01*
G01X212536Y349805D02*
X215400Y346941D01*
Y322382D01*
X222140Y315643D01*
Y300560D01*
X222200Y300500D01*
G01X205915Y422424D02*
X206776D01*
X227100Y402100D01*
Y365600D01*
X228100Y364600D01*
G01X201868Y451187D02*
X200600Y449919D01*
Y444900D01*
X201750Y443750D01*
Y420951D01*
X222200Y400501D01*
Y379183D01*
X223383Y378000D01*
G01X217190Y428485D02*
X215598Y426893D01*
Y426426D01*
X236900Y405124D01*
Y302240D01*
X251109Y288031D01*
Y271929D01*
X287338Y235700D01*
X365900D01*
X415900Y185700D01*
Y160096D01*
X422767Y153229D01*
Y76934D01*
X507551Y-7850D01*
X720465D01*
X726228Y-2087D01*
X752731D01*
X757544Y-6900D01*
X790071D01*
X794992Y-1979D01*
X802279D01*
X808235Y-7935D01*
X963489D01*
X970386Y-1038D01*
X994557D01*
X1006660Y11065D01*
X1017489D01*
X1024004Y4550D01*
X1044911D01*
X1045083Y4378D01*
X1046617D01*
X1046789Y4550D01*
X1083921D01*
X1086800Y7429D01*
Y27897D01*
X1084096Y30601D01*
X1082808D01*
G01X212200Y428800D02*
X213598Y427402D01*
Y425597D01*
X234900Y404295D01*
Y301411D01*
X249109Y287202D01*
Y271100D01*
X286509Y233700D01*
X365071D01*
X413900Y184871D01*
Y159267D01*
X420767Y152400D01*
Y76105D01*
X506722Y-9850D01*
X721294D01*
X727057Y-4087D01*
X751902D01*
X756715Y-8900D01*
X790900D01*
X795821Y-3979D01*
X801450D01*
X807406Y-9935D01*
X964318D01*
X971215Y-3038D01*
X995386D01*
X1007489Y9065D01*
X1016660D01*
X1023175Y2550D01*
X1044082D01*
X1044254Y2378D01*
X1047446D01*
X1047618Y2550D01*
X1084750D01*
X1088800Y6600D01*
Y27068D01*
X1092094Y30362D01*
G01X212000Y438713D02*
X214688D01*
X221601Y431800D01*
X226067D01*
X241400Y416467D01*
Y388328D01*
X239900Y386828D01*
Y304617D01*
X255919Y288598D01*
Y282553D01*
X297872Y240600D01*
X364000D01*
X417796Y186804D01*
Y160322D01*
X425308Y152810D01*
Y76515D01*
X507911Y-6088D01*
X707523D01*
X713132Y-479D01*
X773250D01*
X778729Y5000D01*
X797972D01*
X809308Y-6336D01*
X962655D01*
X977400Y8409D01*
X991338D01*
X997589Y14660D01*
X1011313D01*
X1013961Y17308D01*
X1021509D01*
X1025703Y13114D01*
Y12050D01*
X1029184Y8569D01*
X1050501D01*
X1053000Y6070D01*
X1071370D01*
X1077300Y12000D01*
X1079995D01*
X1080792Y11203D01*
Y9620D01*
X1080672Y9500D01*
G01X217500Y441992D02*
X216600Y441092D01*
Y439630D01*
X222430Y433800D01*
X226896D01*
X243400Y417296D01*
Y387499D01*
X241900Y385999D01*
Y305446D01*
X257919Y289427D01*
Y283382D01*
X298701Y242600D01*
X364829D01*
X419796Y187633D01*
Y161151D01*
X427308Y153639D01*
Y77344D01*
X508740Y-4088D01*
X706694D01*
X712303Y1521D01*
X772421D01*
X777900Y7000D01*
X798801D01*
X810137Y-4336D01*
X961826D01*
X976571Y10409D01*
X990509D01*
X996760Y16660D01*
X1010484D01*
X1013132Y19308D01*
X1022338D01*
X1027703Y13943D01*
Y12879D01*
X1030013Y10569D01*
X1051330D01*
X1053829Y8070D01*
X1070541D01*
X1076471Y14000D01*
X1080824D01*
X1083378Y11446D01*
Y10922D01*
X1084800Y9500D01*
Y9400D01*
G01X228298Y488100D02*
X229198Y487200D01*
X231501D01*
X233600Y485101D01*
Y480972D01*
X231128Y478500D01*
X226428D01*
X224800Y476872D01*
Y444700D01*
X248183Y421317D01*
Y381970D01*
X245511Y379298D01*
Y379128D01*
X244000Y377617D01*
G01X228347Y484700D02*
X228847Y485200D01*
X230672D01*
X231600Y484272D01*
Y481801D01*
X230299Y480500D01*
X225599D01*
X222800Y477701D01*
Y443871D01*
X246183Y420488D01*
Y382799D01*
X245366Y381982D01*
X244000D01*
G01X808114Y67634D02*
X806730Y66250D01*
X796633D01*
X790133Y72750D01*
X769550D01*
X754076Y57276D01*
X713906D01*
X708414Y51784D01*
Y49594D01*
X708415Y49593D01*
Y43375D01*
X684955Y19915D01*
X528282D01*
X497850Y50347D01*
Y62304D01*
X448500Y111654D01*
Y161446D01*
X448000Y161946D01*
Y190666D01*
X379636Y259030D01*
X296154D01*
X251010Y304174D01*
Y371539D01*
X253550Y374079D01*
Y425967D01*
X232717Y446800D01*
X228900D01*
G01X228298Y488100D02*
X227698Y487500D01*
X226900D01*
X225000Y489400D01*
Y498099D01*
X224200Y498899D01*
Y509811D01*
X222800Y511211D01*
Y535166D01*
X218821Y539145D01*
Y542399D01*
X223550Y547128D01*
Y565515D01*
X220010Y569055D01*
Y671086D01*
X202600Y688496D01*
Y691300D01*
X203300Y692000D01*
G01X228347Y484700D02*
X227547Y485500D01*
X226071D01*
X223000Y488571D01*
Y497270D01*
X222200Y498070D01*
Y508982D01*
X220800Y510382D01*
Y534337D01*
X216821Y538316D01*
Y543228D01*
X221550Y547957D01*
Y564686D01*
X218010Y568226D01*
Y670257D01*
X200600Y687667D01*
Y691300D01*
X199900Y692000D01*
G01X219000Y694000D02*
Y681395D01*
X225010Y675385D01*
Y675264D01*
X225249Y675025D01*
Y583602D01*
X234783Y574068D01*
Y572921D01*
X234777Y556282D01*
Y550569D01*
G01X206700Y554500D02*
X209092Y556892D01*
Y653031D01*
X209091Y654274D01*
Y656126D01*
X209092Y657369D01*
Y665308D01*
X201000Y673400D01*
Y674000D01*
G01X206952Y655370D02*
X207091D01*
X207591Y654871D01*
Y652410D01*
X207592Y652409D01*
Y558792D01*
X203447Y554647D01*
Y554684D01*
X203304D01*
G01X288270Y365240D02*
X290100Y367070D01*
Y488578D01*
X282682Y495996D01*
Y505810D01*
X276150Y512342D01*
Y522622D01*
X250388Y548384D01*
Y575710D01*
X244500Y581598D01*
Y686000D01*
X231500Y699000D01*
G01X488462Y190761D02*
X472823Y206400D01*
X444100D01*
X380500Y270000D01*
X300500D01*
X273400Y297100D01*
Y302246D01*
X265450Y310196D01*
Y360350D01*
X267300Y362200D01*
G01X251700Y421600D02*
Y375701D01*
X246310Y370311D01*
Y306225D01*
X261421Y291114D01*
Y288380D01*
X303701Y246100D01*
X368005D01*
X425840Y188265D01*
Y162180D01*
X432386Y155634D01*
Y79339D01*
X502596Y9129D01*
X519264D01*
X522478Y5915D01*
X705096D01*
X711462Y12281D01*
X805318D01*
X812519Y5080D01*
X817574D01*
X820194Y7700D01*
X824248D01*
X829048Y2900D01*
X852468D01*
X853768Y4200D01*
X861825D01*
X864425Y6800D01*
X885585D01*
X891721Y664D01*
X958784D01*
X976932Y18812D01*
X988040D01*
X995591Y26363D01*
X1029737D01*
X1034073Y22027D01*
X1046972D01*
X1049500Y24555D01*
Y31145D01*
X1056685Y38330D01*
Y41847D01*
X1059393Y44555D01*
X1071919D01*
X1074974Y41500D01*
X1076716D01*
X1078694Y43478D01*
G01X251700Y425200D02*
X250936D01*
X249700Y423964D01*
Y376530D01*
X244310Y371140D01*
Y305396D01*
X259421Y290285D01*
Y287551D01*
X302872Y244100D01*
X367176D01*
X423840Y187436D01*
Y161351D01*
X430386Y154805D01*
Y78510D01*
X501767Y7129D01*
X518435D01*
X521649Y3915D01*
X705925D01*
X712291Y10281D01*
X804489D01*
X811690Y3080D01*
X818403D01*
X821023Y5700D01*
X823419D01*
X828219Y900D01*
X853297D01*
X854597Y2200D01*
X862654D01*
X865254Y4800D01*
X884756D01*
X890892Y-1336D01*
X959613D01*
X977761Y16812D01*
X988869D01*
X996420Y24363D01*
X1028908D01*
X1033244Y20027D01*
X1047801D01*
X1051500Y23726D01*
Y30316D01*
X1058685Y37501D01*
Y41018D01*
X1060222Y42555D01*
X1071090D01*
X1074145Y39500D01*
X1080469D01*
X1083315Y36654D01*
G01X376600Y261350D02*
X296663D01*
X253010Y305003D01*
Y370710D01*
X257800Y375500D01*
Y390500D01*
X258500Y391200D01*
G01X381700Y265800D02*
X379650Y267850D01*
X299550D01*
X270366Y297034D01*
Y300120D01*
X269150Y301336D01*
Y301367D01*
X268067Y302450D01*
X268036D01*
X263400Y307087D01*
Y368329D01*
X266950Y371879D01*
Y461783D01*
X254450Y474283D01*
Y492650D01*
X256300Y494500D01*
G01X245400Y296500D02*
X244762D01*
X238400Y302862D01*
Y387450D01*
X239100Y388150D01*
Y399200D01*
G01X456500Y169783D02*
X455317Y168600D01*
X452901D01*
X451500Y170001D01*
Y192117D01*
X377937Y265680D01*
X298720D01*
X259000Y305400D01*
Y320700D01*
X261190Y322890D01*
Y340710D01*
X257300Y344600D01*
Y366300D01*
X263300Y372300D01*
Y396300D01*
X259500Y400100D01*
Y426200D01*
X256774Y428926D01*
Y430819D01*
X257111Y431183D01*
X257116Y431188D01*
X257822Y431216D01*
X264100Y425400D01*
G01X456500Y165418D02*
X455318Y166600D01*
X452072D01*
X449500Y169172D01*
Y191288D01*
X377108Y263680D01*
X297891D01*
X257000Y304571D01*
Y321529D01*
X259190Y323719D01*
Y339881D01*
X255300Y343771D01*
Y367129D01*
X261300Y373129D01*
Y395471D01*
X257500Y399271D01*
Y425371D01*
X254774Y428097D01*
Y431605D01*
X255644Y432543D01*
X255618Y433249D01*
X249342Y439064D01*
G01X238400Y416200D02*
Y415814D01*
X239100Y415114D01*
Y399200D01*
G01X561300Y369500D02*
X558535Y372265D01*
X536535D01*
X275050Y633750D01*
Y647250D01*
X270100Y652200D01*
X256600D01*
G01X286406Y716531D02*
X281375Y711500D01*
X251000D01*
X241000Y721500D01*
G01X307278Y726198D02*
Y725482D01*
X289796Y708000D01*
X245500D01*
X241000Y712500D01*
G01Y725500D02*
X253000Y713500D01*
X279500D01*
X282406Y716406D01*
Y716598D01*
G01X290338Y715800D02*
Y714994D01*
X284844Y709500D01*
X249500D01*
X241000Y718000D01*
G01X635482Y207733D02*
X634694D01*
X626203Y199242D01*
X574459D01*
X565141Y208560D01*
X494243D01*
X489353Y213450D01*
X439250D01*
X381200Y271500D01*
X301600D01*
X274900Y298200D01*
Y302868D01*
X271699Y306069D01*
Y309181D01*
X267420Y313460D01*
Y326143D01*
X269150Y327873D01*
Y341329D01*
X267979Y342500D01*
G01X301320Y362500D02*
Y361220D01*
X293550Y353450D01*
Y309556D01*
X305880Y297226D01*
Y291420D01*
X306800Y290500D01*
G01X299600Y297662D02*
X297488Y299774D01*
Y302789D01*
X291550Y308727D01*
Y358821D01*
X292891Y360162D01*
Y361945D01*
X294009Y363063D01*
G01X279994Y554794D02*
X278350Y553150D01*
Y512264D01*
X284182Y506432D01*
Y496840D01*
X291600Y489422D01*
Y364335D01*
X287200Y359935D01*
Y326802D01*
G01X295400Y325390D02*
Y351735D01*
X303170Y359505D01*
Y367085D01*
X295999Y374256D01*
Y486923D01*
X293721Y489201D01*
Y489423D01*
X288400Y494744D01*
Y504336D01*
X283603Y509133D01*
Y513509D01*
X280200Y516912D01*
Y551400D01*
G01X283700Y322100D02*
X284100Y322500D01*
Y365299D01*
X288100Y369299D01*
Y479600D01*
X282400Y485300D01*
Y487300D01*
G01X311882Y310550D02*
X306570Y315862D01*
Y367929D01*
X299103Y375396D01*
Y377618D01*
X299102Y377620D01*
Y454625D01*
X299200Y454723D01*
Y487966D01*
X296722Y490444D01*
Y503100D01*
X291900Y507922D01*
Y519323D01*
X291896Y519424D01*
X291900Y519448D01*
Y557100D01*
X296200Y561400D01*
Y566900D01*
G01X283600Y551400D02*
Y522100D01*
X288030Y517670D01*
Y510792D01*
X288029Y510791D01*
Y509549D01*
X293440Y504138D01*
X293562D01*
X295221Y502479D01*
Y489823D01*
X297500Y487544D01*
Y411569D01*
X297602Y411467D01*
Y374775D01*
X305070Y367307D01*
Y331870D01*
X303517Y330317D01*
Y309777D01*
G01X302500Y251600D02*
X305810Y248290D01*
X383130D01*
X431027Y200393D01*
Y170577D01*
X431028Y170576D01*
Y164065D01*
X438000Y157093D01*
X437999Y109921D01*
Y84855D01*
X460050Y62804D01*
Y61533D01*
X461133Y60450D01*
X462404D01*
X465127Y57727D01*
G01X302140Y444160D02*
Y375188D01*
X308570Y368758D01*
Y328230D01*
X315900Y320900D01*
G01X320500Y531000D02*
X321421Y530079D01*
X337177D01*
X450656Y416600D01*
X476000D01*
X499642Y392958D01*
Y362401D01*
X476353Y339112D01*
Y334525D01*
X477037Y333841D01*
G01X321000Y527000D02*
X322079Y528079D01*
X336348D01*
X449827Y414600D01*
X475171D01*
X497642Y392129D01*
Y363230D01*
X474353Y339941D01*
Y334592D01*
X474206Y334445D01*
Y334444D01*
X473692Y333930D01*
X473637Y333877D01*
Y333876D01*
G01X345820Y256570D02*
X347770Y254620D01*
X378922D01*
X445000Y188542D01*
Y160702D01*
X445500Y160202D01*
Y110304D01*
X494850Y60952D01*
Y49103D01*
X527038Y16915D01*
X686199D01*
X686288Y17004D01*
X686294D01*
X709507Y40217D01*
X714224D01*
X714226Y40219D01*
X715882D01*
X715883Y40218D01*
X717539D01*
X717540Y40217D01*
X735050D01*
X744733Y49900D01*
X753550D01*
X772644Y68994D01*
X788919D01*
X795013Y62900D01*
X909178D01*
X913628Y67350D01*
X938472D01*
X948822Y77700D01*
X961058D01*
X964326Y80968D01*
Y94388D01*
X960700Y98014D01*
Y110300D01*
X959423Y111577D01*
Y128616D01*
X961097Y130290D01*
X961686D01*
X963100Y131704D01*
Y133100D01*
X964960Y134960D01*
Y135827D01*
G01X349970Y256720D02*
X379824D01*
X446500Y190044D01*
Y161324D01*
X447000Y160824D01*
Y110933D01*
X496350Y61583D01*
Y49725D01*
X527660Y18415D01*
X685577D01*
X708909Y41747D01*
X717365D01*
X722457Y46839D01*
Y50997D01*
X727214Y55754D01*
X756472D01*
X771212Y70494D01*
X789541D01*
X795635Y64400D01*
X908556D01*
X913006Y68850D01*
X937850D01*
X948200Y79200D01*
X960436D01*
X962826Y81590D01*
Y93766D01*
X959200Y97392D01*
Y109400D01*
X955486Y113114D01*
Y128616D01*
X957159Y130289D01*
X957748D01*
X959200Y131741D01*
Y132330D01*
X961097Y134227D01*
X961686D01*
X962623Y135164D01*
Y137427D01*
X964960Y139764D01*
G01X1072800Y-800D02*
X1072700Y-900D01*
Y-7100D01*
X1071500Y-8300D01*
X1062518D01*
X1058259Y-4041D01*
X1050222D01*
X1050141Y-4122D01*
X1046750D01*
X1034437Y-16435D01*
X1023700D01*
X1017068Y-9803D01*
X973884D01*
X967252Y-16435D01*
X504112D01*
X413068Y74609D01*
Y150626D01*
X404915Y158779D01*
Y184585D01*
X400400Y189100D01*
G01X1083500Y25500D02*
X1082191Y26809D01*
X1065073D01*
X1062544Y29338D01*
X1059234D01*
X1048423Y18527D01*
X1029342D01*
X1025006Y22863D01*
X999563D01*
X988886Y12186D01*
X975650D01*
X960628Y-2836D01*
X815166D01*
X803830Y8500D01*
X776900D01*
X772650Y4250D01*
X737600D01*
X734150Y7700D01*
X716055D01*
X710770Y2415D01*
X521027D01*
X517813Y5629D01*
X501145D01*
X428809Y77965D01*
Y154260D01*
X421757Y161312D01*
Y177999D01*
G01X411400Y183900D02*
X412159Y183141D01*
Y158886D01*
X419267Y151778D01*
Y75483D01*
X506185Y-11435D01*
X964940D01*
X971573Y-4802D01*
X1013541D01*
X1019393Y1050D01*
X1043460D01*
X1043632Y878D01*
X1048068D01*
X1048240Y1050D01*
X1081600D01*
X1082150Y500D01*
X1084000D01*
G01X985579Y26494D02*
X987403Y24670D01*
Y22164D01*
X985941Y20702D01*
X981769D01*
X980871Y21600D01*
X969857D01*
X965285Y17028D01*
X891296D01*
X883418Y9150D01*
X864653D01*
X861203Y5700D01*
X853146D01*
X851846Y4400D01*
X829670D01*
X825638Y8432D01*
Y10073D01*
X819971Y15740D01*
X819659D01*
X815499Y19900D01*
X746401D01*
X741331Y14830D01*
X706431D01*
X699016Y7415D01*
X523100D01*
X519886Y10629D01*
X503218D01*
X433887Y79960D01*
Y155772D01*
X433886Y156256D01*
X427527Y162615D01*
Y198942D01*
X425769Y200700D01*
X423746D01*
X422876Y199830D01*
G01X985403Y22993D02*
X985112Y22702D01*
X982598D01*
X981700Y23600D01*
X969028D01*
X964456Y19028D01*
X890467D01*
X882589Y11150D01*
X863824D01*
X860374Y7700D01*
X852317D01*
X851017Y6400D01*
X830499D01*
X827638Y9261D01*
Y10902D01*
X820800Y17740D01*
X820488D01*
X816328Y21900D01*
X745572D01*
X740502Y16830D01*
X705602D01*
X698187Y9415D01*
X523929D01*
X520715Y12629D01*
X504047D01*
X435887Y80789D01*
Y155774D01*
X435885Y157086D01*
X429527Y163444D01*
Y199771D01*
X426598Y202700D01*
X424371D01*
X422876Y204195D01*
G01X433000Y169700D02*
Y164215D01*
X439500Y157715D01*
Y109300D01*
X439499Y109299D01*
Y107643D01*
X488850Y58292D01*
Y46616D01*
X524551Y10915D01*
X697565D01*
X705050Y18400D01*
X735489D01*
X743490Y26401D01*
X774399D01*
X777400Y23400D01*
X816950D01*
X821110Y19240D01*
X824738D01*
X831028Y12950D01*
X877918D01*
X877919Y12949D01*
X880405D01*
X880406Y12950D01*
X882267D01*
X889845Y20528D01*
X958511D01*
X969140Y31157D01*
X1025165D01*
X1028403Y27919D01*
X1031929D01*
X1034828Y25020D01*
X1042872D01*
X1047472Y29620D01*
Y34903D01*
X1052936Y40367D01*
Y41104D01*
X1057887Y46055D01*
X1063004D01*
X1063787Y46838D01*
X1077951D01*
X1083379Y41410D01*
Y40889D01*
G01X438561Y166892D02*
X437958Y166289D01*
Y164915D01*
X443500Y159373D01*
Y109300D01*
X492850Y59950D01*
Y48274D01*
X526209Y14915D01*
X691751D01*
X715054Y38218D01*
X716711Y38217D01*
X744316D01*
X748680Y42581D01*
X759370D01*
X761606Y40345D01*
X838468D01*
X852929Y25884D01*
X859570D01*
X861294Y27608D01*
X880633D01*
X884325Y31300D01*
X920662D01*
X924662Y35300D01*
X953687D01*
X978221Y59834D01*
Y104782D01*
G01X435161Y166892D02*
X435958Y166092D01*
Y164086D01*
X441500Y158544D01*
Y108471D01*
X490850Y59121D01*
Y47445D01*
X525380Y12915D01*
X692580D01*
X715882Y36217D01*
X745145D01*
X749509Y40581D01*
X758541D01*
X760777Y38345D01*
X837639D01*
X852100Y23884D01*
X860399D01*
X862123Y25608D01*
X881462D01*
X885154Y29300D01*
X921491D01*
X925491Y33300D01*
X954516D01*
X980221Y59005D01*
Y105104D01*
G01X918890Y117604D02*
X917500Y116214D01*
Y103245D01*
X916250Y101995D01*
Y99865D01*
X906408Y90023D01*
Y85712D01*
X897110Y76414D01*
X866098D01*
X865548Y76964D01*
X847969D01*
X845155Y74150D01*
X800462D01*
X795562Y79050D01*
X786555D01*
X784755Y77250D01*
X771416D01*
X771415Y77251D01*
X770173D01*
X770172Y77252D01*
X768321D01*
X768311Y77250D01*
X767684D01*
X760878Y70444D01*
X754617D01*
X745950Y61777D01*
X712041D01*
X703914Y53650D01*
Y47728D01*
X703915Y47727D01*
Y45241D01*
X683089Y24415D01*
X530544D01*
X502350Y52609D01*
Y65159D01*
X488116Y79393D01*
Y135197D01*
X511319Y158400D01*
X542181D01*
X545054Y161273D01*
X547240D01*
X549437Y163470D01*
X557162D01*
X561627Y167935D01*
X564483D01*
G01X922500Y114500D02*
X920400Y112400D01*
Y103372D01*
X919250Y102222D01*
Y98621D01*
X911850Y91221D01*
Y84533D01*
X900731Y73414D01*
X863646D01*
X863096Y73964D01*
X849213D01*
X846399Y71150D01*
X799218D01*
X794318Y76050D01*
X787799D01*
X785999Y74250D01*
X770172D01*
X768929Y74251D01*
X753455Y58777D01*
X713285D01*
X706914Y52406D01*
Y48972D01*
X706915Y48971D01*
Y43997D01*
X684333Y21415D01*
X529300D01*
X499350Y51365D01*
Y63915D01*
X485116Y78149D01*
Y138416D01*
X502125Y155425D01*
Y173139D01*
X506336Y177350D01*
X548020D01*
X558121Y167249D01*
G01X535960Y151999D02*
X532159Y155800D01*
X510841D01*
X489616Y134575D01*
Y80015D01*
X503850Y65781D01*
Y53231D01*
X531166Y25915D01*
X682467D01*
X702415Y45863D01*
Y47105D01*
X702414Y47106D01*
Y54272D01*
X711419Y63277D01*
X744605D01*
X753428Y72100D01*
X760412D01*
X767062Y78750D01*
X768162D01*
X768172Y78752D01*
X770794D01*
X770795Y78751D01*
X772037D01*
X772038Y78750D01*
X784133D01*
X785933Y80550D01*
X801572D01*
X804172Y77950D01*
X819289D01*
X821538Y75701D01*
X844584D01*
X847347Y78464D01*
X866170D01*
X866720Y77914D01*
X896488D01*
X903850Y85276D01*
Y90514D01*
X914750Y101414D01*
Y102222D01*
X916217Y103689D01*
Y113700D01*
G01X507300Y175500D02*
Y156504D01*
X486616Y135819D01*
Y78771D01*
X500850Y64537D01*
Y51987D01*
X529922Y22915D01*
X683711D01*
X705415Y44619D01*
Y48349D01*
X705414Y48350D01*
Y53028D01*
X712663Y60277D01*
X752833D01*
X768306Y75750D01*
X768460D01*
X768470Y75752D01*
X769550D01*
X769551Y75751D01*
X770793D01*
X770794Y75750D01*
X785377D01*
X787177Y77550D01*
X794940D01*
X799840Y72650D01*
X845777D01*
X848591Y75464D01*
X864926D01*
X865476Y74914D01*
X897732D01*
X907908Y85090D01*
Y89401D01*
X917750Y99243D01*
Y102222D01*
X919000Y103472D01*
Y115338D01*
G01X529176Y151713D02*
X529163Y151700D01*
X510985D01*
X494693Y135408D01*
Y129406D01*
X502999Y121100D01*
X668356D01*
X702936Y86520D01*
Y81097D01*
X712534Y71499D01*
X713776D01*
X713777Y71500D01*
X748583D01*
X752184Y75100D01*
X758189D01*
X764839Y81750D01*
X767864D01*
X767874Y81752D01*
X772038D01*
X772039Y81751D01*
X773281D01*
X773282Y81750D01*
X782889D01*
X784689Y83550D01*
X804150D01*
X806750Y80950D01*
X820533D01*
X822782Y78701D01*
X843340D01*
X846103Y81464D01*
X867414D01*
X867964Y80914D01*
X891131D01*
X894850Y84633D01*
Y86011D01*
X912243Y103404D01*
Y113500D01*
G01X914900D02*
Y103686D01*
X899450Y88236D01*
Y84733D01*
X894131Y79414D01*
X867342D01*
X866792Y79964D01*
X846725D01*
X843962Y77201D01*
X822160D01*
X819911Y79450D01*
X805250D01*
X802650Y82050D01*
X785311D01*
X783511Y80250D01*
X772660D01*
X772659Y80251D01*
X771417D01*
X771416Y80252D01*
X768023D01*
X768013Y80250D01*
X766440D01*
X759790Y73600D01*
X752806D01*
X743983Y64777D01*
X710797D01*
X700914Y54894D01*
Y46484D01*
X681845Y27415D01*
X531788D01*
X505350Y53853D01*
Y115416D01*
X493193Y127573D01*
Y136030D01*
X511263Y154100D01*
X530506D01*
X532560Y152046D01*
G01X477037Y333841D02*
X476431D01*
X475952Y333361D01*
X475941Y333350D01*
Y332330D01*
X475940Y332278D01*
Y332084D01*
X475933Y330687D01*
X476799Y329816D01*
X492965D01*
X511949Y348800D01*
X534860D01*
X550986Y332674D01*
X610294D01*
X615894Y327074D01*
X623717D01*
X625148Y328505D01*
Y328963D01*
X624101Y330010D01*
G01X473637Y333876D02*
X473941Y333566D01*
Y332350D01*
X473940Y332298D01*
Y332090D01*
X473928Y329866D01*
X475967Y327816D01*
X493794D01*
X512478Y346500D01*
X534331D01*
X550157Y330674D01*
X609465D01*
X615065Y325074D01*
X624546D01*
X627148Y327676D01*
Y329547D01*
X627500Y329899D01*
Y329900D01*
G01X549100Y126900D02*
X556700D01*
X559069Y129269D01*
X559297D01*
X559866Y129838D01*
X561400D01*
X561969Y129269D01*
X609131D01*
X614800Y123600D01*
X667978D01*
X704436Y87142D01*
Y81719D01*
X713155Y73000D01*
X744622D01*
X748822Y77200D01*
X757600D01*
X759600Y79200D01*
G01X541637Y263240D02*
X542805Y262072D01*
Y255341D01*
X545749Y252397D01*
Y233362D01*
X576199Y202912D01*
X613280D01*
X620514Y210146D01*
X641709D01*
X645113Y206742D01*
Y200381D01*
X650697Y194797D01*
X669907D01*
X689505Y175199D01*
X702270D01*
X703941Y176870D01*
X757505D01*
X762202Y172173D01*
Y170202D01*
X761242Y169242D01*
G01X545974Y263240D02*
X544805Y262071D01*
Y256170D01*
X547749Y253226D01*
Y234191D01*
X577028Y204912D01*
X612451D01*
X619685Y212146D01*
X642538D01*
X647113Y207571D01*
Y201210D01*
X651526Y196797D01*
X670736D01*
X690334Y177199D01*
X701441D01*
X703112Y178870D01*
X758334D01*
X764202Y173002D01*
Y170619D01*
X765579Y169242D01*
G01X596253Y210000D02*
X599373Y206880D01*
X611635D01*
X618869Y214114D01*
X643354D01*
X649081Y208387D01*
Y202026D01*
X652342Y198765D01*
X671552D01*
X691150Y179167D01*
X700625D01*
X702296Y180838D01*
X759389D01*
X768777Y171450D01*
G01X576100Y234500D02*
X576650Y233950D01*
X577906D01*
X578256Y233600D01*
X580154D01*
X588196Y225558D01*
X592430D01*
X596122Y229250D01*
X605546D01*
X605548Y229252D01*
X611205D01*
X616970Y235017D01*
G01X614721Y138287D02*
X614924Y138490D01*
Y142524D01*
X616900Y144500D01*
X617000D01*
G01X729000Y24800D02*
X738417Y34217D01*
X828198D01*
X830242Y36261D01*
X833698D01*
X849051Y20908D01*
G01X845052Y20800D02*
X834792Y31061D01*
X830203D01*
X828547Y32717D01*
X740327D01*
X730560Y22950D01*
X727115D01*
X725314Y24751D01*
G01X721890Y24887D02*
Y22883D01*
X723323Y21450D01*
X731182D01*
X740949Y31217D01*
X773983D01*
X778150Y27050D01*
X805249D01*
X807319Y29120D01*
X833332D01*
X841652Y20800D01*
G01X838252D02*
X831432Y27620D01*
X807941D01*
X805871Y25550D01*
X778772D01*
X778771Y25549D01*
X777529D01*
X773361Y29717D01*
X741571D01*
X731804Y19950D01*
X721057D01*
X719008Y21999D01*
G01X766950Y189252D02*
X767885Y190187D01*
Y190202D01*
X769348Y191665D01*
X776220D01*
X777324Y190561D01*
X784083D01*
X787691Y186953D01*
Y174095D01*
X792252Y169534D01*
X820302D01*
X822536Y167300D01*
X847200D01*
X848823Y168923D01*
X883177D01*
X883200Y168900D01*
G01X763562Y189539D02*
X768188Y194165D01*
X777256D01*
X777906Y193515D01*
X777907D01*
X778361Y193061D01*
X807668D01*
X826929Y173800D01*
X844359D01*
X845334Y172825D01*
X882118D01*
G01X770385Y189165D02*
Y188609D01*
X769026Y187250D01*
Y182919D01*
X786911Y165034D01*
X817766D01*
X820000Y162800D01*
X848300D01*
X850486Y164986D01*
X879309D01*
X879495Y164800D01*
G01X964105Y62308D02*
X960700Y58903D01*
X959470D01*
X959116Y59257D01*
X959088D01*
X958100Y60245D01*
X929878D01*
X922772Y53139D01*
Y39395D01*
X916784Y33407D01*
X910247D01*
X909804Y33850D01*
X852228D01*
X831378Y54700D01*
X786796D01*
X775381Y66115D01*
G01X778800Y66388D02*
X788988Y56200D01*
X865923D01*
X877123Y45000D01*
X900776D01*
X910869Y34907D01*
X916162D01*
X921272Y40017D01*
Y58854D01*
X924768Y62350D01*
X958655D01*
X959855Y61150D01*
Y61107D01*
G01X782551Y67144D02*
X790995Y58700D01*
X900972D01*
X905193Y54479D01*
X905488D01*
G01X909797Y55037D02*
X903834Y61000D01*
X792296D01*
X786333Y66963D01*
G01X803265Y174050D02*
X805281Y172034D01*
X823036D01*
X825270Y169800D01*
X846636D01*
X846700Y169864D01*
X883363D01*
G01X880400Y166500D02*
X849300D01*
X847600Y164800D01*
X821500D01*
X819266Y167034D01*
X790979D01*
X785156Y172857D01*
Y184978D01*
X782325Y187809D01*
X775293D01*
X773984Y189118D01*
G01X1049772Y57259D02*
X1048082D01*
X1048032Y57309D01*
X1035688D01*
X1029919Y51540D01*
Y44295D01*
X1027359Y41735D01*
X1022118D01*
X1017987Y37604D01*
X962647D01*
X952343Y27300D01*
X886268D01*
X880718Y21750D01*
X876372D01*
X875857Y22265D01*
X865365D01*
X862050Y18950D01*
X836350D01*
X834500Y20800D01*
G01X830500D02*
X830700D01*
X834050Y17450D01*
X862750D01*
X866065Y20765D01*
X875235D01*
X875750Y20250D01*
X880096D01*
X880097Y20249D01*
X881339D01*
X886890Y25800D01*
X952965D01*
X963269Y36104D01*
X1018609D01*
X1022698Y40193D01*
X1028152D01*
X1031419Y43460D01*
Y50661D01*
X1036567Y55809D01*
X1047410D01*
X1049470Y53749D01*
G01X828283Y24734D02*
Y20303D01*
X832636Y15950D01*
X879162D01*
X887512Y24300D01*
X953587D01*
X963891Y34604D01*
X1019231D01*
X1023061Y38434D01*
X1029746D01*
X1035545Y32635D01*
Y30827D01*
X1037072Y29300D01*
X1043565D01*
X1044050Y28815D01*
G01X1033554Y30216D02*
X1033223Y30547D01*
Y32378D01*
X1028667Y36934D01*
X1023683D01*
X1019853Y33104D01*
X968852D01*
X958819Y23071D01*
X954480D01*
X954209Y22800D01*
X888134D01*
X879783Y14449D01*
X878541D01*
X878540Y14450D01*
X831650D01*
X824462Y21638D01*
Y25770D01*
G01X823551Y80551D02*
X825968Y82968D01*
X868032D01*
X868586Y82414D01*
X887931D01*
X891050Y85533D01*
Y86067D01*
X892133Y87150D01*
X892189D01*
X911000Y105961D01*
Y114500D01*
G01X806665Y174050D02*
X823850D01*
X826100Y171800D01*
X883340D01*
X883745Y172205D01*
G01X848623Y70757D02*
X849026D01*
X852519Y67264D01*
X908264D01*
X924100Y83100D01*
Y94983D01*
X925250Y96133D01*
Y104850D01*
X931000Y110600D01*
G01X926700Y117900D02*
Y114500D01*
X922000Y109800D01*
Y103472D01*
X920750Y102222D01*
Y97999D01*
X919600Y96849D01*
Y89078D01*
X902436Y71914D01*
X861878D01*
X861328Y72464D01*
X853894D01*
X852019Y70589D01*
G01X931078Y114466D02*
X924350Y107738D01*
Y102822D01*
X923750Y102222D01*
Y96755D01*
X922600Y95605D01*
Y84311D01*
X907053Y68764D01*
X857208D01*
X855421Y70551D01*
G01X927921Y114200D02*
X923450Y109729D01*
Y103422D01*
X922250Y102222D01*
Y97377D01*
X921100Y96227D01*
Y84933D01*
X906581Y70414D01*
X859021D01*
X858821Y70614D01*
G01X909843Y155512D02*
Y149943D01*
X908243Y148343D01*
Y107243D01*
X898850Y97850D01*
Y95933D01*
X896917Y94000D01*
X894911D01*
X888888Y87977D01*
X887960D01*
X887333Y87350D01*
X884233D01*
X880797Y83914D01*
X870186D01*
X868800Y85300D01*
G01X861406Y804403D02*
X859900Y802897D01*
Y788040D01*
X850650Y778790D01*
Y742750D01*
X858900Y734500D01*
Y705278D01*
X859922Y704256D01*
X865284D01*
X865550Y704522D01*
Y705278D01*
X864800Y706028D01*
Y707700D01*
G01X857406Y804403D02*
X858400Y803409D01*
Y788662D01*
X849150Y779412D01*
Y742128D01*
X857400Y733878D01*
Y704656D01*
X859300Y702756D01*
X865906D01*
X867050Y703900D01*
Y704878D01*
X868200Y706028D01*
Y707700D01*
G01X984645Y151575D02*
X982570Y149500D01*
X975900D01*
X975000Y148600D01*
Y118874D01*
X974500Y118374D01*
Y107719D01*
X973751Y106970D01*
Y79975D01*
X959626Y65850D01*
X922321D01*
X915904Y59433D01*
Y41451D01*
X915486Y41030D01*
G01X978371Y124900D02*
Y119416D01*
X976500Y117545D01*
Y106890D01*
X975751Y106141D01*
Y79146D01*
X960455Y63850D01*
X923150D01*
X917904Y58604D01*
Y41728D01*
X918952Y40680D01*
G01X935100Y113800D02*
Y112100D01*
X929800Y106800D01*
Y105900D01*
G01X964960Y131890D02*
Y130460D01*
X963300Y128800D01*
Y111240D01*
X962200Y110140D01*
Y105644D01*
X965700Y102144D01*
Y95136D01*
X965846Y94990D01*
Y80346D01*
X961300Y75800D01*
X956445D01*
X953895Y73250D01*
X951733D01*
X950019Y74964D01*
X949102D01*
G01X959300Y68600D02*
X957450Y70450D01*
Y72900D01*
X958850Y74300D01*
X961922D01*
X967346Y79724D01*
Y95612D01*
X967201Y95757D01*
Y141299D01*
X964960Y143540D01*
Y143701D01*
G01X959300Y72000D02*
X960099Y72799D01*
X962543D01*
X970497Y80753D01*
Y152238D01*
X968897Y153838D01*
Y155512D01*
G01X949893Y106378D02*
X950227D01*
X952400Y108551D01*
Y111000D01*
X951549Y111851D01*
Y128849D01*
X952990Y130290D01*
X953812D01*
X954749Y131227D01*
Y131449D01*
X954900Y131600D01*
Y133127D01*
X956000Y134227D01*
X957749D01*
X958686Y135164D01*
Y137427D01*
X961023Y139764D01*
G01X949828Y109778D02*
Y124172D01*
X947500Y126500D01*
Y128700D01*
X951488Y132688D01*
X951500D01*
X952812Y134000D01*
X953900D01*
X954749Y134849D01*
Y149238D01*
X957086Y151575D01*
G01X994650Y39880D02*
Y43317D01*
X996130Y44797D01*
X1011921D01*
X1028167Y61043D01*
X1040241D01*
G01X1033017Y14743D02*
X1033022D01*
X1033179Y14900D01*
X1045141D01*
X1046662Y13379D01*
X1051004D01*
X1051833Y12550D01*
X1058350D01*
X1060800Y10100D01*
G01X1251801Y144871D02*
Y144765D01*
X1248097Y141061D01*
Y131796D01*
X1237732Y121431D01*
X1140232D01*
X1072815Y54014D01*
X1064597D01*
X1061139Y50556D01*
X1055673D01*
X1054757Y49640D01*
X1039384D01*
X1036854Y47110D01*
G01X1047500Y41500D02*
X1050880Y44880D01*
X1052119D01*
X1056295Y49056D01*
X1061761D01*
X1063720Y51015D01*
X1066206D01*
X1080859Y51014D01*
X1092829D01*
X1096843Y47000D01*
X1104622D01*
X1117272Y59650D01*
X1117528D01*
X1117529Y59651D01*
X1118771D01*
X1118772Y59650D01*
X1146472D01*
X1147122Y59000D01*
X1162378D01*
X1162928Y59550D01*
X1191072D01*
X1191623Y58999D01*
X1202324D01*
X1213128Y69803D01*
G01X1256435D02*
Y68935D01*
X1250500Y63000D01*
X1237500D01*
X1235000Y60500D01*
X1207500D01*
X1204000Y57000D01*
X1191500D01*
X1190450Y58050D01*
X1163550D01*
X1163000Y57500D01*
X1146500D01*
X1145850Y58150D01*
X1118150D01*
X1105500Y45500D01*
X1095518D01*
X1091504Y49514D01*
X1065585D01*
X1064342Y49515D01*
X1062382Y47555D01*
X1056916D01*
X1051000Y41639D01*
Y41500D01*
G01X1105441Y54768D02*
X1104300Y55909D01*
Y57000D01*
X1126552Y79252D01*
X1129466D01*
G01X1100992Y52374D02*
X1100875Y52491D01*
Y55697D01*
X1126513Y81335D01*
Y84764D01*
G01X1088287Y55917D02*
X1089730Y54474D01*
X1095974D01*
X1100448Y50000D01*
X1103378D01*
X1123181Y69803D01*
X1126513D01*
G01X1169820D02*
Y68320D01*
X1162500Y61000D01*
X1162256D01*
X1161756Y60500D01*
X1147744D01*
X1146794Y61450D01*
X1116950D01*
X1104000Y48500D01*
X1099222D01*
X1096496Y51226D01*
G01X1297400Y651300D02*
X1296288D01*
X1295550Y652038D01*
Y695050D01*
X1304678Y704178D01*
Y731422D01*
X1306128Y732872D01*
G01X1290550Y651300D02*
X1291400D01*
X1294450Y654350D01*
Y695506D01*
X1303578Y704634D01*
Y731422D01*
X1302128Y732872D01*
G54D14*
X1116671Y-315D03*
X1159978D03*
X1203285D03*
X1246592D03*
X1289899D03*
G54D24*
G01X137661Y614096D02*
X136097Y615660D01*
X132953D01*
X131369Y617244D01*
G54D15*
X1138324Y37520D03*
X1181631D03*
X1224939D03*
X1268246D03*
G54D25*
G01X83500Y344200D02*
X82751Y343451D01*
G03X82526Y342908I543J-543D01*
G01Y338284D01*
X81941Y335530D01*
X80428Y333200D01*
X70518Y326766D01*
X70146Y326194D01*
X69675Y323482D01*
X73503Y305325D01*
X74780Y303358D01*
X76522Y301616D01*
X84250Y296595D01*
X86987Y283713D01*
X83680Y268151D01*
X87040Y252360D01*
X111082Y228318D01*
X146431Y205362D01*
X184890Y197188D01*
X194296Y199188D01*
X207914Y196293D01*
X221847Y199255D01*
X241540Y212045D01*
X270813Y218267D01*
X283156Y215645D01*
X296763Y218537D01*
X302057Y217413D01*
X312847Y219706D01*
X359930Y209697D01*
X370000Y203157D01*
X380998Y186224D01*
X383465Y174614D01*
X381972Y167593D01*
X384596Y155250D01*
X386763Y151912D01*
X397502Y144942D01*
X402500D01*
X403600Y146042D01*
G01X80300Y344200D02*
X80967Y343533D01*
G02X81226Y342908I-625J-625D01*
G01Y338421D01*
X80719Y336036D01*
X79488Y334140D01*
X69578Y327707D01*
X68910Y326680D01*
X68351Y323458D01*
X72280Y304820D01*
X73764Y302535D01*
X75699Y300600D01*
X83090Y295798D01*
X85657Y283713D01*
X82350Y268151D01*
X85848Y251712D01*
X110259Y227302D01*
X145925Y204140D01*
X184890Y195858D01*
X194296Y197858D01*
X207914Y194963D01*
X222353Y198033D01*
X242046Y210823D01*
X270813Y216937D01*
X283156Y214315D01*
X296763Y217207D01*
X302057Y216083D01*
X312847Y218376D01*
X336137Y213425D01*
Y213424D01*
X359424Y208475D01*
X369060Y202217D01*
X379776Y185718D01*
X382135Y174614D01*
X380642Y167593D01*
X383374Y154744D01*
X385823Y150972D01*
X397117Y143642D01*
X402500D01*
X403600Y142542D01*
G01X401300Y156715D02*
X400200Y155615D01*
X395504D01*
X393633Y156013D01*
X391350Y157495D01*
X390392Y158970D01*
X388573Y167526D01*
X389982Y174154D01*
X387087Y187774D01*
X374048Y207852D01*
X361073Y216277D01*
X308869Y227375D01*
X283372Y221955D01*
X270954Y224593D01*
X237584Y217500D01*
X220325Y221168D01*
X220056Y221111D01*
Y221110D01*
X189623Y214649D01*
X123443Y228717D01*
X109316Y237892D01*
X92213Y264229D01*
X90932Y270247D01*
X94327Y286216D01*
X91271Y300592D01*
X88185Y305343D01*
X81856Y309452D01*
X77243Y316555D01*
X76473Y320173D01*
Y321522D01*
X77421Y322470D01*
G01X401300Y153215D02*
X400200Y154315D01*
X395367D01*
X393127Y154791D01*
X390410Y156554D01*
X389170Y158464D01*
X387243Y167526D01*
X388652Y174154D01*
X385865Y187268D01*
X373108Y206912D01*
X360567Y215055D01*
X308869Y226045D01*
X283372Y220625D01*
X270954Y223263D01*
X237584Y216170D01*
X220325Y219838D01*
X189623Y213319D01*
X122937Y227495D01*
X108376Y236952D01*
X90991Y263722D01*
X89602Y270247D01*
X92997Y286216D01*
X90049Y300086D01*
X87245Y304403D01*
X80916Y308512D01*
X76021Y316048D01*
X75173Y320036D01*
Y321518D01*
X74221Y322470D01*
G01X147117Y610945D02*
X147392Y610670D01*
Y604508D01*
X148700Y603200D01*
X151144D01*
X151844Y602500D01*
Y597694D01*
X150543Y596393D01*
Y587457D01*
X151800Y586200D01*
X155000D01*
X155500Y585700D01*
Y584600D01*
X154300Y583400D01*
Y581400D01*
X155500Y580200D01*
Y579123D01*
X155000Y578623D01*
X149261D01*
X148000Y577362D01*
Y575084D01*
X149261Y573823D01*
X154955D01*
X155505Y573273D01*
Y571600D01*
X155005Y571100D01*
X149437D01*
X148176Y569839D01*
Y567161D01*
X149437Y565900D01*
X151465D01*
X152104Y565261D01*
Y564404D01*
X150600Y562900D01*
Y560464D01*
X152264Y558800D01*
Y557413D01*
X151989Y557138D01*
G01X162865Y601495D02*
X162561D01*
X161966Y600900D01*
Y600166D01*
X166055Y596077D01*
Y559721D01*
X163434Y557100D01*
X162280D01*
X161280Y556100D01*
G01X150268Y610944D02*
X149136D01*
X148692Y610500D01*
Y605047D01*
X149239Y604500D01*
X151683D01*
X153144Y603039D01*
Y597155D01*
X151843Y595854D01*
Y587996D01*
X152339Y587500D01*
X155539D01*
X156800Y586239D01*
Y584061D01*
X155600Y582861D01*
Y581939D01*
X156800Y580739D01*
Y578584D01*
X155539Y577323D01*
X149800D01*
X149300Y576823D01*
Y575623D01*
X149800Y575123D01*
X155494D01*
X156805Y573812D01*
Y571061D01*
X155544Y569800D01*
X149976D01*
X149476Y569300D01*
Y567700D01*
X149976Y567200D01*
X152004D01*
X153404Y565800D01*
Y563865D01*
X151900Y562361D01*
Y561003D01*
X153564Y559339D01*
Y556413D01*
X151989Y554838D01*
G01X159716Y601495D02*
Y600577D01*
X161671Y598621D01*
X163862Y596431D01*
X164755Y595538D01*
Y560260D01*
X162895Y558400D01*
X161280D01*
G01X194120Y830301D02*
G03X193170Y827675I3154J-2626D01*
G01Y827192D01*
G02X192235Y824935I-3192J0D01*
G03X191300Y822678I2257J-2257D01*
G01Y820053D01*
X191798Y817230D01*
X193856Y814291D01*
X195600Y811800D01*
X222279Y793119D01*
X282500Y782500D01*
X294692Y773963D01*
X332994Y767210D01*
X626226Y561890D01*
X766180Y362014D01*
X775088Y311502D01*
X769711Y281008D01*
X771235Y272364D01*
X774295Y267994D01*
X780289Y263797D01*
X798911Y260514D01*
X807500Y254500D01*
X809570Y251544D01*
X813934Y226829D01*
X832017Y201004D01*
X847158Y190713D01*
X854904Y189347D01*
X858939Y186523D01*
X863170Y185776D01*
X869831Y181112D01*
X869854Y181108D01*
X871437D01*
G01Y179808D02*
X869741D01*
X869322Y179880D01*
X862660Y184545D01*
X858429Y185292D01*
X854394Y188116D01*
X846660Y189480D01*
Y189479D01*
X846657Y189480D01*
X831088Y200062D01*
X812703Y226319D01*
X808339Y251034D01*
X806566Y253566D01*
X798401Y259283D01*
X779779Y262566D01*
X773361Y267060D01*
X770004Y271854D01*
X768390Y281008D01*
X773767Y311502D01*
X764949Y361504D01*
X625292Y560956D01*
X332484Y765979D01*
X294182Y772732D01*
X281990Y781269D01*
X221769Y791888D01*
X194666Y810866D01*
X190567Y816720D01*
X190000Y819939D01*
Y822678D01*
G02X191315Y825855I4492J1D01*
G03X191870Y827192I-1336J1338D01*
G01Y828500D01*
G03X191268Y829952I-2052J0D01*
G01X190920Y830301D01*
G01X228550Y772700D02*
G02X229500Y770641I-1756J-2059D01*
G01Y735300D01*
X229497Y735285D01*
X233844Y710650D01*
G03X234150Y709910I1822J320D01*
G01X240694Y700562D01*
X241012Y700244D01*
X241014D01*
X250803Y693388D01*
G03X251543Y693082I1061J1517D01*
G01X267473Y690273D01*
G03X268117I322J1823D01*
G01X286205Y693462D01*
G02X286395I95J-541D01*
G01X322713Y687058D01*
G03X323357I322J1823D01*
G01X354005Y692462D01*
G02X354195I95J-541D01*
G01X391127Y685950D01*
G02X391347Y685859I-95J-541D01*
G01X465787Y633736D01*
G02X465922Y633601I-315J-450D01*
G01X498879Y586533D01*
G03X499333Y586079I1516J1062D01*
G01X573604Y534075D01*
G02X573739Y533940I-315J-450D01*
G01X612662Y478352D01*
G03X613116Y477898I1516J1062D01*
G01X638296Y460268D01*
X677972Y403777D01*
G02X678062Y403558I-451J-313D01*
G01X681200Y385766D01*
Y379818D01*
X680100Y378718D01*
G01X683600D02*
X682500Y379818D01*
Y385880D01*
X679343Y403784D01*
G03X679037Y404523I-1822J-321D01*
G01X639229Y461202D01*
X613862Y478963D01*
G02X613727Y479098I316J451D01*
G01X574804Y534686D01*
G03X574350Y535140I-1515J-1061D01*
G01X500079Y587144D01*
G02X499944Y587279I316J451D01*
G01X466987Y634347D01*
G03X466533Y634801I-1515J-1061D01*
G01X392093Y686925D01*
G03X391353Y687231I-1060J-1516D01*
G01X354421Y693743D01*
G03X353779I-321J-1822D01*
G01X323131Y688339D01*
G02X322939I-96J542D01*
G01X286621Y694743D01*
G03X285979I-321J-1822D01*
G01X267891Y691554D01*
G02X267699I-96J542D01*
G01X251769Y694363D01*
G02X251549Y694454I95J542D01*
G01X241760Y701309D01*
X235216Y710656D01*
G02X235125Y710875I450J315D01*
G01Y710876D01*
X230778Y735510D01*
X230800Y735635D01*
Y770900D01*
G02X231401Y772351I2052J0D01*
G01X231750Y772700D01*
G01X219317Y830301D02*
G03X218367Y827675I3154J-2626D01*
G01Y820473D01*
X225000Y811000D01*
X230002Y807497D01*
X231033Y807679D01*
X232384Y806733D01*
X232566Y805702D01*
X233918Y804756D01*
X234948Y804937D01*
X236300Y803991D01*
X236482Y802960D01*
X242756Y798567D01*
X326583Y783786D01*
X635592Y567415D01*
X810594Y317486D01*
X815000Y292500D01*
X812003Y275500D01*
X820148Y229303D01*
X836106Y206509D01*
X849687Y196999D01*
X872272Y193015D01*
X872814Y193111D01*
G01X206718Y830301D02*
G03X205768Y827675I3154J-2626D01*
G01Y826029D01*
X217535Y809225D01*
X219778Y807654D01*
X220809Y807835D01*
X222160Y806889D01*
X222342Y805858D01*
X223694Y804912D01*
X224724Y805094D01*
X226076Y804147D01*
X226258Y803117D01*
X230173Y800375D01*
X236910Y795658D01*
X326992Y779774D01*
X632760Y565672D01*
X633807Y564626D01*
X807267Y316900D01*
X811641Y292092D01*
X808583Y274750D01*
X816822Y228025D01*
X833797Y203782D01*
X847451Y194221D01*
X856064Y192703D01*
X856065D01*
X857256Y192493D01*
X858583Y191564D01*
X870475Y189466D01*
X870482Y189465D01*
X875666Y188983D01*
G01X873559Y197147D02*
X872014Y198692D01*
X859994D01*
X855766Y199437D01*
X851363Y200213D01*
X842072Y206718D01*
X838168Y212293D01*
X820728Y311195D01*
X638752Y571084D01*
X334190Y784340D01*
X252815Y798688D01*
X236566Y810066D01*
X229665Y819923D01*
Y827675D01*
G03X228715Y830301I-4104J0D01*
G01X216117D02*
G02X217067Y827675I-3154J-2626D01*
G01Y820063D01*
X224066Y810066D01*
X242246Y797336D01*
X326073Y782555D01*
X634658Y566481D01*
X809363Y316976D01*
X813679Y292500D01*
X810682Y275500D01*
X818917Y228793D01*
X835172Y205575D01*
X849177Y195769D01*
Y195768D01*
X872272Y191694D01*
X873040Y191830D01*
G01X203518Y830301D02*
G02X204468Y827675I-3154J-2626D01*
G01Y825619D01*
X216601Y808291D01*
X219032Y806589D01*
X219031Y806588D01*
X229426Y799309D01*
X236400Y794427D01*
X326482Y778543D01*
X631921Y564672D01*
X632807Y563786D01*
X806036Y316390D01*
X810320Y292092D01*
X807262Y274750D01*
X815591Y227515D01*
X832863Y202848D01*
X846941Y192990D01*
X856746Y191262D01*
X858073Y190333D01*
X870361Y188166D01*
X875720Y187672D01*
X875891Y187702D01*
X876433Y187797D01*
G01X874739Y197806D02*
X872553Y199992D01*
X860108D01*
X851873Y201444D01*
X843006Y207652D01*
X839399Y212803D01*
X821959Y311705D01*
X639686Y572018D01*
X334700Y785571D01*
X273791Y796310D01*
X273191Y797168D01*
X271566Y797454D01*
X270708Y796854D01*
X269084Y797140D01*
X268483Y797998D01*
X266858Y798284D01*
X266001Y797684D01*
X253325Y799919D01*
X237500Y811000D01*
X230965Y820333D01*
Y827675D01*
G02X231915Y830301I4104J0D01*
G01X872600Y205200D02*
X861300D01*
X852116Y206820D01*
X848027Y209683D01*
X842458Y217637D01*
X825168Y315692D01*
X645000Y573000D01*
X333085Y791405D01*
X305229Y796317D01*
X301157Y797035D01*
X300032Y797233D01*
X299431Y798090D01*
X297806Y798377D01*
X296949Y797777D01*
X295324Y798063D01*
X294724Y798920D01*
X293099Y799207D01*
X292242Y798607D01*
X268032Y802876D01*
X260000Y808500D01*
X253012Y818480D01*
Y827675D01*
G02X253962Y830301I4104J0D01*
G01X873000Y207900D02*
X862486D01*
X856921Y208880D01*
X849717Y213925D01*
X843266Y223138D01*
X826430Y318620D01*
X646179Y576022D01*
X334490Y794269D01*
X328685Y795292D01*
X295564Y801132D01*
X278633Y804118D01*
X270589Y809750D01*
X264311Y818717D01*
Y827675D01*
G03X263361Y830301I-4104J0D01*
G01X872600Y203900D02*
X861186D01*
X856483Y204729D01*
X851606Y205589D01*
X847093Y208749D01*
X841227Y217127D01*
X823937Y315182D01*
X644066Y572066D01*
X332575Y790174D01*
X305003Y795035D01*
X300333Y795859D01*
X267522Y801645D01*
X259066Y807566D01*
X251712Y818070D01*
Y827675D01*
G03X250762Y830301I-4104J0D01*
G01X873000Y209200D02*
X862600D01*
X857431Y210111D01*
X850651Y214859D01*
X844497Y223648D01*
X827661Y319130D01*
X647113Y576956D01*
X335000Y795500D01*
X328911Y796573D01*
X315486Y798941D01*
X295790Y802414D01*
X292171Y803052D01*
X291082Y803244D01*
X290482Y804101D01*
X288857Y804388D01*
X288000Y803787D01*
X286375Y804074D01*
X285775Y804931D01*
X284150Y805218D01*
X283292Y804617D01*
X279143Y805349D01*
X271523Y810684D01*
X265611Y819127D01*
Y827675D01*
G02X266561Y830301I4104J0D01*
G01X873200Y213200D02*
X864100D01*
X859730Y213971D01*
X853723Y218177D01*
X849292Y224505D01*
X832657Y318854D01*
X650378Y579170D01*
X335000Y800000D01*
X311243Y804189D01*
X308160Y804733D01*
X306535Y805019D01*
X305935Y805876D01*
X304310Y806163D01*
X303453Y805563D01*
X301828Y805849D01*
X301228Y806706D01*
X299603Y806993D01*
X298746Y806393D01*
X290600Y807829D01*
X282500Y813500D01*
X278209Y819628D01*
Y827200D01*
G02X279159Y830301I5536J0D01*
G01X873200Y211900D02*
X863986D01*
X859220Y212740D01*
X852789Y217243D01*
X848061Y223995D01*
X831426Y318344D01*
X649444Y578236D01*
X334490Y798769D01*
X311017Y802907D01*
X290090Y806598D01*
X281566Y812566D01*
X276909Y819218D01*
Y827200D01*
G03X275959Y830301I-5536J0D01*
G01X873100Y217200D02*
X864847D01*
X862177Y217671D01*
X857977Y220612D01*
X853996Y226297D01*
X837472Y320007D01*
Y320008D01*
X651050Y586248D01*
X648951Y587717D01*
X334735Y807735D01*
X327811Y812594D01*
X327631Y813624D01*
X326280Y814572D01*
X325249Y814391D01*
X323899Y815339D01*
X323718Y816370D01*
X322367Y817318D01*
X321337Y817137D01*
X319799Y818216D01*
X316004Y823635D01*
Y827675D01*
G02X316954Y830301I4104J0D01*
G01X326353D02*
G02X327303Y827675I-3154J-2626D01*
G01Y822795D01*
X336566Y809566D01*
X652880Y588081D01*
X840049Y320775D01*
X856355Y228300D01*
X859918Y223212D01*
X864293Y220149D01*
X866279Y219800D01*
X873100D01*
G01Y215900D02*
X864733D01*
X861667Y216440D01*
X857043Y219678D01*
X852765Y225787D01*
X836241Y319498D01*
X650116Y585314D01*
X648205Y586652D01*
X333989Y806670D01*
X318865Y817283D01*
X314704Y823224D01*
Y827675D01*
G03X313754Y830301I-4104J0D01*
G01X329553D02*
G03X328603Y827675I3154J-2626D01*
G01Y823205D01*
X329980Y821238D01*
X331011Y821057D01*
X331957Y819705D01*
X331776Y818674D01*
X332722Y817323D01*
X333753Y817141D01*
X334699Y815790D01*
X334518Y814759D01*
X337500Y810500D01*
X653814Y589015D01*
X841280Y321285D01*
X857586Y228810D01*
X860852Y224146D01*
X864803Y221380D01*
X866393Y221100D01*
X873100D01*
G01X341652Y305034D02*
X342752Y303934D01*
X360937D01*
X361637Y304634D01*
X363287D01*
X363987Y303934D01*
X365637D01*
X388310Y299115D01*
X436851Y309800D01*
X478782Y300837D01*
X537686Y313369D01*
X539473Y313749D01*
Y313750D01*
X540924Y314057D01*
X544796Y316571D01*
X547560Y320827D01*
X551529Y323404D01*
X554800Y324100D01*
X565438D01*
G02X567081Y323418I-2J-2324D01*
G01X568606Y321894D01*
G03X570438Y321135I1833J1833D01*
G01X589168D01*
X589868Y321835D01*
X591518D01*
X592218Y321135D01*
X593868D01*
X594568Y321835D01*
X596218D01*
X596918Y321135D01*
X598568D01*
X599268Y321835D01*
X600918D01*
X601618Y321135D01*
X628018D01*
G03X632614Y323444I0J5729D01*
G01X649352Y345945D01*
X657532Y351257D01*
X659301D01*
X660244Y352200D01*
G01X341652Y301534D02*
X342752Y302634D01*
X365500D01*
X388315Y297784D01*
X412585Y303127D01*
X436855Y308469D01*
X478781Y299507D01*
X537962Y312098D01*
X537985Y312103D01*
X538119Y312131D01*
X538290Y312168D01*
X541430Y312835D01*
X545736Y315631D01*
X545886Y315861D01*
Y315862D01*
X548500Y319887D01*
X552035Y322182D01*
X554937Y322800D01*
X565437D01*
G02X566161Y322499I-1J-1024D01*
G01X567686Y320974D01*
G03X570438Y319835I2751J2754D01*
G01X628017D01*
G03X633657Y322668I1J7029D01*
G01X650256Y344981D01*
X657918Y349957D01*
X659287D01*
X660244Y349000D01*
G01X364354Y731801D02*
Y730612D01*
G03X364523Y730204I577J0D01*
G01X366465Y728262D01*
G03X367339Y727900I874J874D01*
G01X376200D01*
G02X383404Y725465I0J-11874D01*
G01X622665Y557933D01*
X759778Y362113D01*
X769292Y308159D01*
X763850Y277306D01*
Y276014D01*
X771795Y230971D01*
X776469Y224299D01*
X782631Y219986D01*
X792182Y218302D01*
X803068Y220222D01*
X810000Y219000D01*
X815485Y215160D01*
X828523Y196539D01*
X852018Y180964D01*
X865683Y180465D01*
X867948Y178200D01*
X875861D01*
X876900Y179239D01*
G02X877289Y179400I389J-389D01*
G01X878172D01*
G03X878561Y179561I0J550D01*
G01X885350Y186350D01*
G02X889575Y188100I4226J-4227D01*
G01X942693D01*
G02X943965Y187574I0J-1801D01*
G01X944474Y187065D01*
G02X945000Y185793I-1275J-1272D01*
G01Y144600D01*
G01X943700D02*
Y185793D01*
G03X943554Y186146I-500J0D01*
G01X943046Y186654D01*
G03X942693Y186800I-353J-354D01*
G01X889576D01*
G03X886269Y185430I0J-4677D01*
G01X879085Y178246D01*
G02X878732Y178100I-353J354D01*
G01X877600D01*
X876400Y176900D01*
X867409D01*
X865125Y179184D01*
X851605Y179678D01*
X827599Y195591D01*
X814551Y214226D01*
X809490Y217769D01*
X803068Y218901D01*
X792182Y216981D01*
X782121Y218755D01*
X775536Y223365D01*
X770564Y230461D01*
X762550Y275900D01*
Y277420D01*
X767971Y308159D01*
X758547Y361603D01*
X758546Y361604D01*
X645255Y523404D01*
X644224Y523585D01*
X643278Y524937D01*
X643459Y525968D01*
X621731Y556999D01*
X381865Y724955D01*
G03X376200Y726600I-5665J-8932D01*
G01X367339D01*
G02X365545Y727342I-1J2537D01*
G01X363602Y729285D01*
G03X362991Y729538I-611J-611D01*
G01X362091D01*
G01X367348Y830301D02*
G03X366398Y827200I4586J-3101D01*
G01Y816818D01*
X369903Y813313D01*
X377532Y805683D01*
X391547Y803212D01*
X667910Y609703D01*
X852450Y346153D01*
X856673Y322206D01*
X864553Y277515D01*
X868026Y257819D01*
X868884Y257219D01*
X869170Y255594D01*
X868570Y254737D01*
X868856Y253112D01*
X869714Y252512D01*
X870000Y250887D01*
X869400Y250029D01*
X869686Y248404D01*
X870332Y244745D01*
X871864Y236055D01*
X873439Y233806D01*
G01X354750Y830301D02*
G03X353800Y827675I3154J-2626D01*
G01Y816477D01*
X362144Y804561D01*
X660000Y596000D01*
X850208Y324355D01*
X852073Y313778D01*
X854399Y300588D01*
X857750Y281585D01*
X860032Y268638D01*
X863426Y249391D01*
X864036Y245934D01*
X864256Y244684D01*
X865114Y244084D01*
X865400Y242459D01*
X864800Y241601D01*
X865087Y239976D01*
X865944Y239376D01*
X866230Y237751D01*
X865630Y236894D01*
X866329Y232930D01*
X868140Y230344D01*
X869693Y229257D01*
X871150Y229000D01*
X872600D01*
G01X342151Y830301D02*
G03X341201Y827675I3154J-2626D01*
G01Y819355D01*
X348592Y808800D01*
X657500Y592500D01*
X844677Y325184D01*
X847389Y309810D01*
X849727Y296549D01*
X853065Y277617D01*
X855410Y264319D01*
X856533Y257950D01*
X857165Y254368D01*
X857297Y253618D01*
X857907Y250161D01*
X858742Y245424D01*
X859362Y241907D01*
X859572Y240716D01*
X860429Y240116D01*
X860716Y238491D01*
X860115Y237634D01*
X860402Y236009D01*
X861259Y235409D01*
X861546Y233784D01*
X860945Y232926D01*
X861340Y230688D01*
X863061Y228231D01*
X867205Y225329D01*
X869070Y225000D01*
X873300D01*
G01X364148Y830301D02*
G02X365098Y827200I-4586J-3101D01*
G01Y816279D01*
X368439Y812938D01*
X376902Y804473D01*
X391037Y801981D01*
X666976Y608769D01*
X851219Y345643D01*
X863272Y277289D01*
X869050Y244519D01*
X870633Y235545D01*
X872006Y233585D01*
G01X351550Y830301D02*
G02X352500Y827675I-3154J-2626D01*
G01Y816066D01*
X361210Y803627D01*
X659066Y595066D01*
X848977Y323845D01*
X853117Y300362D01*
X858751Y268412D01*
X862145Y249165D01*
X865098Y232420D01*
X867207Y229410D01*
X869183Y228026D01*
X871036Y227700D01*
X872700D01*
G01X338951Y830301D02*
G02X339901Y827675I-3154J-2626D01*
G01Y818945D01*
X347658Y807866D01*
X656566Y591566D01*
X843446Y324674D01*
X848445Y296322D01*
X854128Y264092D01*
X855882Y254141D01*
X856623Y249934D01*
X858079Y241680D01*
X860109Y230178D01*
X862127Y227297D01*
X866695Y224098D01*
X868956Y223700D01*
X873300D01*
G01X389396Y830301D02*
G03X388446Y827675I3154J-2626D01*
G01Y818149D01*
X394528Y809463D01*
X670386Y616308D01*
X855415Y352059D01*
X857609Y339620D01*
X870627Y265811D01*
X870626D01*
X870736Y265194D01*
G03X871526Y263226I5120J913D01*
G01X873388Y261364D01*
G03X873563Y261205I1702J1698D01*
G03X873981Y260930I1523J1860D01*
G01X874062Y260888D01*
G03X874311Y260827I249J478D01*
G02X876501Y259920I0J-3097D01*
G01X876510Y259911D01*
G03X877164Y259640I654J654D01*
G01X877398D01*
G03X878325Y260024I0J1311D01*
G01X878446Y260144D01*
G03X878800Y261000I-856J855D01*
G03X878548Y261610I-862J1D01*
G01X878347Y261810D01*
G01X386196Y830301D02*
G02X387146Y827675I-3154J-2626D01*
G01Y817738D01*
X393594Y808529D01*
X669452Y615374D01*
X854184Y351549D01*
X869461Y264930D01*
X869650Y263856D01*
X869705Y263543D01*
G03X870070Y262842I1294J228D01*
G01X872468Y260444D01*
G03X872738Y260199I2622J2618D01*
G03X873382Y259775I2348J2866D01*
G01X873463Y259734D01*
G03X874311Y259527I848J1632D01*
G02X874368Y259526I-3J-1797D01*
G01Y259527D01*
G02X875541Y259041I0J-1659D01*
G01X875551Y259031D01*
G03X878347Y257873I2796J2796D01*
G01X401994Y830301D02*
G03X401044Y827675I3154J-2626D01*
G01Y822898D01*
X416144Y801333D01*
X673037Y621452D01*
X859989Y354457D01*
X874624Y271454D01*
X877784Y266942D01*
G01X398794Y830301D02*
G02X399744Y827675I-3154J-2626D01*
G01Y822488D01*
X415210Y800399D01*
X672103Y620518D01*
X858758Y353947D01*
X873393Y270944D01*
X876813Y266062D01*
G01X888946Y263900D02*
Y270676D01*
X891823Y285061D01*
X879763Y345361D01*
X679528Y631326D01*
X433379Y803675D01*
X428662Y810411D01*
X426241Y824139D01*
Y827675D01*
G02X427191Y830301I4104J0D01*
G01X414593D02*
G03X413643Y827675I3154J-2626D01*
G01Y823135D01*
X414441Y818609D01*
X427953Y799311D01*
X677693Y624443D01*
X871369Y347846D01*
X884881Y271192D01*
X884900Y271081D01*
Y263700D01*
G01X423991Y830301D02*
G02X424941Y827675I-3154J-2626D01*
G01Y824023D01*
X427431Y809901D01*
X432445Y802741D01*
X678594Y630392D01*
X878541Y344838D01*
X890497Y285061D01*
X887646Y270806D01*
Y263900D01*
G01X883600Y263700D02*
Y270967D01*
X870138Y347336D01*
X676759Y623509D01*
X427019Y798377D01*
X413210Y818099D01*
X412343Y823018D01*
Y827675D01*
G03X411393Y830301I-4104J0D01*
G01X871203Y156831D02*
X864200D01*
X834200Y151542D01*
X803900Y156884D01*
X791531Y154703D01*
X773029Y157965D01*
X756767Y155098D01*
X682513Y168208D01*
X673569Y174017D01*
X643520Y180402D01*
X579506Y166796D01*
X563637Y156492D01*
X563431Y155523D01*
X562047Y154625D01*
X561079Y154831D01*
X559695Y153932D01*
X559489Y152964D01*
X558105Y152065D01*
X557137Y152271D01*
X552250Y149098D01*
X541904Y146900D01*
X524639D01*
G03X522302Y145931I1J-3306D01*
G01X518733Y142363D01*
G03X518350Y141438I925J-925D01*
G01Y139686D01*
G03X519165Y138871I815J0D01*
G01X519300D01*
G01X872400Y152894D02*
X863100D01*
X833548Y147683D01*
X803600Y152965D01*
X792501Y151008D01*
X774201Y154234D01*
X758999Y151554D01*
X679111Y165659D01*
X670350Y171348D01*
X644947Y176747D01*
X601319Y167466D01*
X600780Y166636D01*
X599166Y166292D01*
X598336Y166831D01*
X596722Y166488D01*
X596183Y165658D01*
X594569Y165314D01*
X593739Y165853D01*
X592125Y165510D01*
X591586Y164680D01*
X589972Y164336D01*
X589142Y164875D01*
X587528Y164532D01*
X586989Y163702D01*
X585375Y163358D01*
X584545Y163897D01*
X582931Y163554D01*
X557401Y146974D01*
X547902Y144957D01*
G03X546575Y144236I553J-2600D01*
G02X544919Y143550I-1656J1656D01*
G01X539483D01*
X538783Y142850D01*
X537133D01*
X536433Y143550D01*
X534783D01*
X534083Y142850D01*
X532433D01*
X531733Y143550D01*
X530083D01*
G03X529227Y142694I0J-856D01*
G01Y141523D01*
G03X530042Y140708I815J0D01*
G01X530177D01*
G01X516100Y138871D02*
X516235D01*
G03X517050Y139686I0J815D01*
G01Y141437D01*
G02X517813Y143283I2609J2D01*
G01X521382Y146851D01*
G02X524639Y148200I3257J-3257D01*
G01X541766D01*
X541767Y148201D01*
X551744Y150320D01*
X579000Y168018D01*
X643520Y181732D01*
X674075Y175239D01*
X683000Y169443D01*
X756767Y156419D01*
X773029Y159286D01*
X791531Y156024D01*
X803900Y158205D01*
X834200Y152863D01*
X864086Y158131D01*
X871203D01*
G01X526977Y140708D02*
X527112D01*
G03X527927Y141523I0J815D01*
G01Y142694D01*
G02X530083Y144850I2156J0D01*
G01X544919D01*
G03X545655Y145156I-1J1041D01*
G02X547632Y146229I2799J-2799D01*
G01X556895Y148196D01*
X582425Y164776D01*
X644947Y178077D01*
X670856Y172570D01*
X679598Y166894D01*
X758999Y152875D01*
X774201Y155555D01*
X792501Y152329D01*
X803600Y154286D01*
X833548Y149004D01*
X862976Y154194D01*
X872400D01*
G01X544800Y137769D02*
X544665D01*
G02X543850Y138584I0J815D01*
G01Y139755D01*
G02X544505Y140410I655J0D01*
G01X546748D01*
G03X549037Y141087I1J4204D01*
G01X550561Y142077D01*
X550562D01*
G02X550813Y142223I1752J-2723D01*
G01Y142224D01*
X550816Y142226D01*
G02X551652Y142528I1508J-2866D01*
G01X564078Y145171D01*
X572508Y151221D01*
X573485Y151061D01*
X574825Y152023D01*
X574985Y153000D01*
X576326Y153962D01*
X577303Y153802D01*
X578643Y154764D01*
X578803Y155741D01*
X580585Y157020D01*
X613063Y163937D01*
X617784Y167286D01*
X644516Y172978D01*
X668553Y167882D01*
X675868Y163132D01*
X704029Y158160D01*
X704629Y157302D01*
X706254Y157016D01*
X707111Y157616D01*
X708736Y157329D01*
X709336Y156471D01*
X710961Y156184D01*
X711818Y156784D01*
X713443Y156498D01*
X714043Y155640D01*
X715668Y155353D01*
X716526Y155953D01*
X718151Y155667D01*
X718751Y154809D01*
X720375Y154522D01*
X721233Y155122D01*
X760879Y148123D01*
X773848Y150409D01*
X792647Y147097D01*
X803157Y148948D01*
X832888Y143738D01*
X863055Y149050D01*
X871800D01*
G01X541600Y137769D02*
X541735D01*
G03X542550Y138584I0J815D01*
G01Y139755D01*
G02X544505Y141710I1955J0D01*
G01X546749D01*
G03X548329Y142178I-1J2903D01*
G01X550175Y143377D01*
X550211D01*
G02X551382Y143800I2113J-4017D01*
G01X563541Y146386D01*
X580048Y158235D01*
X580056Y158237D01*
X612530Y165153D01*
X617251Y168502D01*
X644515Y174308D01*
X669059Y169104D01*
X676355Y164367D01*
X760879Y149444D01*
X773848Y151730D01*
X792647Y148418D01*
X803156Y150268D01*
X832887Y145058D01*
X862941Y150350D01*
X871606D01*
G01X872400Y160768D02*
X861993D01*
X846482Y158033D01*
X845915Y157222D01*
X844290Y156936D01*
X843479Y157504D01*
X841854Y157217D01*
X841286Y156406D01*
X839661Y156120D01*
X838850Y156688D01*
X832746Y155611D01*
X803429Y160781D01*
X791001Y158590D01*
X773173Y161732D01*
X755660Y158645D01*
X684086Y171254D01*
X674663Y177372D01*
X674597Y177438D01*
X644201Y183901D01*
X572924Y168749D01*
X568161Y165658D01*
X567954Y164689D01*
X566570Y163791D01*
X565602Y163997D01*
X564218Y163099D01*
X564011Y162131D01*
X562627Y161233D01*
X561659Y161439D01*
X559241Y159870D01*
X557644Y159453D01*
X557144Y158599D01*
X555547Y158183D01*
X554693Y158683D01*
X549456Y157317D01*
X548349Y156210D01*
G03X547800Y154885I1324J-1325D01*
G01Y153100D01*
G03X548700Y152200I900J0D01*
G01X545500D02*
G03X546500Y153200I0J1000D01*
G01Y154885D01*
G02X547429Y157130I3174J1D01*
G01X548786Y158486D01*
X558708Y161076D01*
Y161075D01*
X558710Y161077D01*
X558711Y161076D01*
X572418Y169971D01*
X644201Y185231D01*
X675342Y178609D01*
X675485Y178389D01*
X684572Y172489D01*
X755660Y159966D01*
X773173Y163053D01*
X791001Y159911D01*
X803429Y162102D01*
X832746Y156932D01*
X861879Y162068D01*
X872400D01*
G01X548451Y830301D02*
G03X547500Y828007I2293J-2295D01*
G01X547501D01*
Y777772D01*
X575000Y738500D01*
X648083Y687326D01*
X885095Y348839D01*
X896066Y286622D01*
X892800Y270292D01*
Y263700D01*
G01X891500D02*
Y270422D01*
X894743Y286637D01*
X883864Y348329D01*
X647149Y686392D01*
X574066Y737566D01*
X546201Y777362D01*
Y828007D01*
X546200Y828008D01*
X546205Y828228D01*
G03X545456Y830096I-2559J58D01*
G01X545251Y830301D01*
G01X561050D02*
X560914Y830165D01*
G03X560100Y828200I1965J-1965D01*
G01Y771420D01*
X580000Y743000D01*
X649430Y694384D01*
X887931Y353769D01*
X899718Y286924D01*
Y284994D01*
X896700Y269902D01*
Y263894D01*
G01X557850Y830301D02*
X557986Y830165D01*
G02X558800Y828200I-1965J-1965D01*
G01Y771010D01*
X579066Y742066D01*
X648496Y693450D01*
X886700Y353259D01*
X898418Y286810D01*
Y285125D01*
X895400Y270035D01*
Y263600D01*
G01X577650Y137780D02*
X577118Y138312D01*
G02X576700Y139321I1009J1009D01*
G01Y139902D01*
G02X577507Y141850I2755J0D01*
G01X578377Y142720D01*
X582537Y145421D01*
X585976Y146152D01*
X589003Y146795D01*
X594781Y145566D01*
X599218Y146508D01*
X606707Y152230D01*
X621968Y155602D01*
X634016Y163426D01*
X641155Y164942D01*
X643708Y165392D01*
X664557Y160962D01*
X691281Y142249D01*
X710204Y138913D01*
X721605Y140923D01*
X731850Y139117D01*
X743002Y141082D01*
X753701Y139196D01*
X757904Y139937D01*
X758715Y139369D01*
X760340Y139655D01*
X760908Y140466D01*
X762533Y140753D01*
X763344Y140185D01*
X764968Y140471D01*
X765536Y141282D01*
X771790Y142384D01*
X791191Y138965D01*
X803202Y141082D01*
X832900Y135846D01*
X862600Y141083D01*
X871203D01*
G01X587850Y137800D02*
G02X587000Y139700I1699J1900D01*
G01Y140643D01*
G02X587465Y141765I1586J0D01*
G01X587885Y142185D01*
G02X588756Y142546I871J-870D01*
G01X589767D01*
G02X591059Y142410I-2J-6228D01*
G01X592578Y142088D01*
G03X593607Y142089I512J2428D01*
G01X595768Y142548D01*
X596598Y142009D01*
X598212Y142352D01*
X598751Y143182D01*
X600365Y143525D01*
X609562Y149492D01*
X622347Y152210D01*
X635203Y160559D01*
X641737Y161946D01*
X643654Y162284D01*
X659726Y158869D01*
X666987Y154154D01*
X689049Y138706D01*
X709250Y135145D01*
X721400Y137287D01*
X731750Y135462D01*
X742000Y137268D01*
X753749Y135197D01*
X772298Y131927D01*
X802950Y137330D01*
X831650Y132272D01*
X860300Y137321D01*
X865500Y136405D01*
X869700Y137146D01*
X872300D01*
G01Y133209D02*
X871100D01*
X865501Y132222D01*
X859450Y133287D01*
X831699Y128396D01*
X803401Y133384D01*
X772400Y127920D01*
X760514Y130016D01*
X759704Y129448D01*
X758079Y129734D01*
X757511Y130545D01*
X755886Y130832D01*
X755075Y130264D01*
X753450Y130550D01*
X752882Y131361D01*
X742000Y133280D01*
X731551Y131437D01*
X721150Y133270D01*
X709250Y131173D01*
X686547Y135175D01*
X656049Y156531D01*
X643600Y159175D01*
X642319Y158950D01*
X638370Y158112D01*
X624282Y148963D01*
X615000Y146990D01*
X612822Y144812D01*
X612418Y144741D01*
X612109Y144687D01*
X607067Y143798D01*
X603956Y141622D01*
X603500Y139820D01*
Y139335D01*
G03X603928Y138302I1461J0D01*
G01X604450Y137780D01*
G01X574450D02*
X574982Y138312D01*
G03X575400Y139321I-1009J1009D01*
G01Y139903D01*
G02X576587Y142770I4056J0D01*
G01X577554Y143736D01*
X582031Y146643D01*
X585706Y147424D01*
X589003Y148125D01*
X594781Y146896D01*
X598661Y147720D01*
X606146Y153438D01*
X621458Y156821D01*
X633510Y164648D01*
X640907Y166219D01*
X643731Y166717D01*
X665086Y162179D01*
X691791Y143480D01*
X710204Y140234D01*
X721605Y142244D01*
X731850Y140438D01*
X743002Y142403D01*
X753701Y140517D01*
X771790Y143705D01*
X791191Y140286D01*
X803202Y142403D01*
X832900Y137167D01*
X862486Y142383D01*
X871203D01*
G01X584650Y137800D02*
G03X585700Y139700I-1194J1900D01*
G01Y140643D01*
G02X586545Y142685I2887J1D01*
G01X586965Y143105D01*
G02X588756Y143846I1790J-1791D01*
G01X589768D01*
G02X591329Y143682I-2J-7528D01*
G01X592847Y143360D01*
G03X593336Y143361I242J1156D01*
G01X599859Y144747D01*
X609056Y150714D01*
X621841Y153432D01*
X634697Y161781D01*
X641489Y163223D01*
X643677Y163609D01*
X660232Y160091D01*
X667714Y155232D01*
X689559Y139937D01*
X709250Y136466D01*
X715100Y137497D01*
X721400Y138608D01*
X731750Y136783D01*
X742000Y138589D01*
X753975Y136478D01*
X772298Y133248D01*
X802950Y138651D01*
X817525Y136082D01*
X831650Y133593D01*
X860300Y138642D01*
X862283Y138292D01*
X865500Y137726D01*
X869586Y138446D01*
X872300D01*
G01X601250Y137780D02*
X601772Y138302D01*
G03X602200Y139335I-1033J1033D01*
G01Y139982D01*
X602814Y142410D01*
X606557Y145029D01*
X610624Y145746D01*
X612192Y146022D01*
X612193D01*
X614353Y148182D01*
X623776Y150185D01*
X637864Y159334D01*
X638101Y159385D01*
Y159384D01*
X640075Y159803D01*
X642071Y160227D01*
X643623Y160500D01*
X656578Y157748D01*
X687057Y136406D01*
X709250Y132494D01*
X714975Y133503D01*
X721150Y134591D01*
X731551Y132758D01*
X742000Y134601D01*
X772400Y129241D01*
X803401Y134705D01*
X831699Y129717D01*
X859450Y134608D01*
X865501Y133543D01*
X870987Y134511D01*
X871000Y134509D01*
X872300D01*
G01X597350Y149950D02*
G02X596400Y151576I917J1626D01*
G01Y154304D01*
X596816Y155339D01*
X599276Y157063D01*
X614641Y160335D01*
X619363Y163685D01*
X644013Y168933D01*
X665212Y164428D01*
X683406Y152612D01*
X731507Y142387D01*
X747990Y145891D01*
X754666Y144472D01*
X758627Y143773D01*
X772198Y146164D01*
X792370Y142608D01*
X803624Y144591D01*
X831881Y139609D01*
X862574Y145020D01*
X872100D01*
G01X594150Y149950D02*
G03X595100Y151576I-917J1626D01*
G01Y154556D01*
X595753Y156183D01*
X598746Y158280D01*
X614108Y161551D01*
X618830Y164901D01*
X644013Y170263D01*
X665718Y165650D01*
X683912Y153834D01*
X731507Y143717D01*
X747990Y147221D01*
X754914Y145749D01*
Y145750D01*
X758627Y145094D01*
X772198Y147485D01*
X792370Y143929D01*
X803624Y145912D01*
X831881Y140930D01*
X862457Y146320D01*
X872100D01*
G01X586246Y830301D02*
G03X585296Y828007I2294J-2294D01*
G01X585300Y828003D01*
Y763854D01*
X595000Y750000D01*
X652086Y710028D01*
X894483Y363850D01*
X908101Y286622D01*
X904600Y269118D01*
Y263700D01*
G01X573648Y830301D02*
X573441Y830094D01*
G03X572698Y828300I1794J-1794D01*
G01Y766068D01*
X585000Y748500D01*
X651586Y701876D01*
X890335Y360907D01*
X903709Y285061D01*
X900600Y269516D01*
Y263600D01*
G01X583046Y830301D02*
G02X583996Y828007I-2294J-2294D01*
G01X584000Y828003D01*
Y763444D01*
X594066Y749066D01*
X651152Y709094D01*
X893252Y363340D01*
X906778Y286637D01*
X903300Y269248D01*
Y263700D01*
G01X570448Y830301D02*
X570655Y830094D01*
G02X571398Y828300I-1794J-1794D01*
G01Y765658D01*
X584066Y747566D01*
X650652Y700942D01*
X889104Y360397D01*
X902386Y285076D01*
X899300Y269646D01*
Y263600D01*
G01X912400Y263700D02*
Y279431D01*
X914926Y292061D01*
X912426Y304561D01*
X914926Y317061D01*
X912426Y329561D01*
X914926Y342061D01*
X912426Y354561D01*
X914926Y367061D01*
X912426Y379561D01*
X914991Y392384D01*
X624982Y771025D01*
X624888Y771162D01*
X622162Y775054D01*
X597895Y809712D01*
Y828007D01*
G02X598845Y830301I3244J0D01*
G01X911100Y263700D02*
Y279561D01*
X913600Y292061D01*
X911100Y304561D01*
X913600Y317061D01*
X911100Y329561D01*
X913600Y342061D01*
X911100Y354561D01*
X913600Y367061D01*
X911100Y379561D01*
X913600Y392061D01*
X623929Y770260D01*
X623819Y770420D01*
X621097Y774308D01*
X596595Y809302D01*
Y828007D01*
G03X595645Y830301I-3244J0D01*
G01X627826Y137880D02*
X627223Y138483D01*
G02X626876Y139321I838J838D01*
G01Y141036D01*
G02X627583Y142743I2414J0D01*
G01X630047Y145207D01*
G02X630754Y145500I707J-706D01*
G01X655475D01*
X658800Y144433D01*
X682275Y127996D01*
X683900Y127710D01*
X684468Y126899D01*
X686093Y126612D01*
X686904Y127180D01*
X688529Y126894D01*
X689096Y126083D01*
X690721Y125796D01*
X691532Y126364D01*
X693157Y126078D01*
X693725Y125267D01*
X695350Y124980D01*
X696161Y125548D01*
X697786Y125262D01*
X698354Y124451D01*
X699979Y124165D01*
X700790Y124732D01*
X708637Y123349D01*
X719903Y125333D01*
X723270Y124739D01*
X725022Y124431D01*
X727694Y123960D01*
X729030Y123725D01*
X730592Y123450D01*
X736421Y124477D01*
X766619Y119143D01*
X772364Y120156D01*
X782750Y122008D01*
X788338Y120555D01*
X802056Y124742D01*
X830131Y119790D01*
X848884Y123099D01*
X855952Y124345D01*
X863407Y123031D01*
X864950Y121950D01*
X868413Y118487D01*
G03X869051Y117983I2465J2465D01*
G03X870900Y117460I1847J3001D01*
G01X871900D01*
G01X880957Y114100D02*
Y113011D01*
X879196Y111250D01*
X874615D01*
X860100Y114153D01*
X854104Y112954D01*
X847600Y111653D01*
X802387Y120696D01*
X789116Y116431D01*
X782333Y118271D01*
X771210Y116431D01*
X766210Y115598D01*
X738089Y120554D01*
X732963Y119650D01*
X729254Y120303D01*
X725769Y120917D01*
X721128Y121737D01*
X714524Y120573D01*
X712816Y120272D01*
X705982Y119067D01*
X682605Y123188D01*
X673675Y128996D01*
X672707Y128791D01*
X671323Y129690D01*
X671118Y130659D01*
X669735Y131558D01*
X668767Y131353D01*
X667383Y132253D01*
X667178Y133221D01*
X665795Y134121D01*
X664827Y133915D01*
X663443Y134815D01*
X663238Y135783D01*
X661855Y136683D01*
X645679Y139536D01*
G02X643228Y140812I797J4522D01*
G03X641218Y141646I-2012J-2010D01*
G01X638975D01*
G03X637200Y139871I0J-1775D01*
G01Y139321D01*
G03X637547Y138483I1185J0D01*
G01X638150Y137880D01*
G01X624626D02*
X625229Y138483D01*
G03X625576Y139321I-838J838D01*
G01Y141036D01*
G02X626663Y143663I3715J1D01*
G01X629127Y146127D01*
G02X630754Y146800I1626J-1627D01*
G01X655593D01*
G02X655761Y146774I1J-550D01*
G01X659306Y145636D01*
G02X659453Y145563I-168J-523D01*
G01Y145564D01*
X682785Y129227D01*
X708633Y124671D01*
Y124670D01*
X719903Y126654D01*
X727920Y125241D01*
X728587Y125123D01*
X729255Y125006D01*
X730592Y124771D01*
X736421Y125798D01*
X736647Y125759D01*
Y125758D01*
X751632Y123112D01*
X766619Y120464D01*
X768407Y120779D01*
X769377Y120950D01*
X772137Y121437D01*
X782802Y123338D01*
X788310Y121906D01*
X801975Y126077D01*
X830131Y121111D01*
X848658Y124380D01*
X852193Y125003D01*
X855951Y125665D01*
X856496Y125570D01*
X858972Y125134D01*
X861768Y124641D01*
X863917Y124262D01*
X865789Y122950D01*
X869328Y119411D01*
G03X869734Y119091I1570J1574D01*
G03X870900Y118760I1167J1892D01*
G01X871900D01*
G01X879657Y114100D02*
Y113550D01*
X878657Y112550D01*
X874744D01*
X860100Y115479D01*
X850725Y113605D01*
X847600Y112979D01*
X802311Y122038D01*
X789085Y117787D01*
X782400Y119600D01*
X770997Y117714D01*
X766216Y116917D01*
X752376Y119357D01*
X741798Y121222D01*
X738089Y121875D01*
X732963Y120971D01*
X731223Y121277D01*
X731222Y121278D01*
X721128Y123058D01*
X705982Y120388D01*
X683092Y124423D01*
X662342Y137918D01*
X645905Y140817D01*
G02X644148Y141732I571J3242D01*
G03X641217Y142946I-2931J-2931D01*
G01X638975D01*
G03X635900Y139871I0J-3075D01*
G01Y139321D01*
G02X635553Y138483I-1185J0D01*
G01X634950Y137880D01*
G01X874410Y124016D02*
G02X872775Y124144I-4J10456D01*
G02X870200Y124901I1637J10327D01*
G01X869489Y125611D01*
X867282Y127819D01*
X867237Y127827D01*
X864696Y129606D01*
X861521Y130165D01*
X859197Y130575D01*
X856045Y130020D01*
X853116Y129504D01*
X848069Y128614D01*
X839683Y127136D01*
X831295Y125658D01*
X817326Y128120D01*
X802907Y130662D01*
X784475Y127412D01*
X766978Y124326D01*
X736525Y129698D01*
X733901Y129235D01*
X731299Y128777D01*
X726264Y129664D01*
X721226Y130553D01*
X721004Y130592D01*
X721000Y130572D01*
X720886D01*
X709050Y128486D01*
X684907Y132743D01*
X654404Y154101D01*
X643190Y156334D01*
X639957Y155572D01*
X638585Y154461D01*
G03X637900Y153022I1167J-1438D01*
G01Y151162D01*
G02X636950Y149650I-1678J0D01*
G01X611443Y830301D02*
G03X610493Y828007I2294J-2294D01*
G01Y806065D01*
X660211Y756347D01*
X679772Y742650D01*
X916506Y404561D01*
X919006Y392061D01*
X916506Y379561D01*
X919006Y367061D01*
X916506Y354561D01*
X919006Y342061D01*
X916506Y329561D01*
X919006Y317061D01*
X916506Y304561D01*
X919006Y292061D01*
X916400Y279033D01*
Y263800D01*
G01X608243Y830301D02*
G02X609193Y828007I-2294J-2294D01*
G01Y805526D01*
X659372Y755347D01*
X678838Y741716D01*
X915284Y404038D01*
X917680Y392061D01*
X915180Y379561D01*
X917680Y367061D01*
X915180Y354561D01*
X917680Y342061D01*
X915180Y329561D01*
X917680Y317061D01*
X915180Y304561D01*
X917680Y292061D01*
X915100Y279163D01*
Y263800D01*
G01X920300Y263700D02*
Y278645D01*
X922983Y292061D01*
X920483Y304561D01*
X922983Y317061D01*
X920483Y329561D01*
X922983Y342061D01*
X920483Y354561D01*
X922983Y367061D01*
X920483Y379561D01*
X922983Y392061D01*
X919402Y409964D01*
X657500Y784000D01*
X636421Y798760D01*
X623092Y817795D01*
Y828007D01*
G02X624042Y830301I3244J0D01*
G01X919000Y263700D02*
Y278775D01*
X921657Y292061D01*
X919157Y304561D01*
X921657Y317061D01*
X919157Y329561D01*
X921657Y342061D01*
X919157Y354561D01*
X921657Y367061D01*
X919157Y379561D01*
X921657Y392061D01*
X918180Y409441D01*
X656566Y783066D01*
X635487Y797826D01*
X621792Y817385D01*
Y828007D01*
G03X620842Y830301I-3244J0D01*
G01X924200Y263700D02*
Y278257D01*
X926961Y292061D01*
X924461Y304561D01*
X926961Y317061D01*
X924461Y329561D01*
X926961Y342061D01*
X924461Y354561D01*
X926961Y367061D01*
X924461Y379561D01*
X926961Y392061D01*
X919773Y428269D01*
X664000Y793551D01*
X659981Y796365D01*
X635690Y820656D01*
Y828007D01*
G02X636640Y830301I3244J0D01*
G01X922900Y263700D02*
Y278387D01*
X925635Y292061D01*
X923135Y304561D01*
X925635Y317061D01*
X923135Y329561D01*
X925635Y342061D01*
X923135Y354561D01*
X925635Y367061D01*
X923135Y379561D01*
X925635Y392062D01*
X922093Y409905D01*
X918551Y427747D01*
X663066Y792617D01*
X659142Y795365D01*
X634390Y820117D01*
Y828007D01*
G03X633440Y830301I-3244J0D01*
G01X640150Y149650D02*
G02X639200Y151162I728J1512D01*
G01Y153022D01*
G02X639404Y153450I551J0D01*
G01X640545Y154374D01*
X643213Y155003D01*
X653882Y152879D01*
X684397Y131512D01*
X709040Y127166D01*
Y127164D01*
X721000Y129272D01*
X731299Y127456D01*
X734127Y127954D01*
X736525Y128377D01*
X766978Y123005D01*
X784701Y126131D01*
X802907Y129341D01*
X831295Y124337D01*
X848295Y127333D01*
X853342Y128223D01*
X859197Y129254D01*
X864186Y128375D01*
X866491Y126762D01*
Y126761D01*
X866517Y126743D01*
X868569Y124691D01*
X868570D01*
X869448Y123814D01*
G03X872572Y122860I4962J10658D01*
G02X873967Y122360I1J-2194D01*
G01X874199Y122169D01*
G02X874410Y120079I-948J-1151D01*
G01X643750Y321500D02*
G02X642800Y323794I2295J2294D01*
G01Y324146D01*
G02X643431Y325669I2153J0D01*
G02X644954Y326300I1523J-1522D01*
G01X648200D01*
X665965Y323168D01*
X683913Y326333D01*
X701411Y329418D01*
X737898Y322984D01*
X749300Y315000D01*
X754595Y307437D01*
X757593Y290433D01*
X756012Y281462D01*
X765669Y226690D01*
X770585Y219673D01*
X778853Y213884D01*
X789846Y211945D01*
X801500Y214000D01*
X804558Y213460D01*
X804559D01*
X807617Y212921D01*
X810340Y211014D01*
X823176Y192680D01*
X846040Y176672D01*
X853319Y175389D01*
X854403Y175350D01*
X864599D01*
X865449Y174500D01*
X878350D01*
X879200Y175350D01*
X880197D01*
X881381Y176534D01*
X882872D01*
G01X640550Y321500D02*
G03X641500Y323794I-2295J2294D01*
G01Y324146D01*
G02X642511Y326589I3454J1D01*
G02X644954Y327600I2442J-2443D01*
G01X648266D01*
G02X648361Y327592I2J-550D01*
G01X665870Y324506D01*
G03X666060I95J542D01*
G01X674827Y326052D01*
X701411Y330739D01*
X738408Y324215D01*
X750234Y315934D01*
X755826Y307947D01*
X758914Y290433D01*
X757333Y281462D01*
X766900Y227200D01*
X771518Y220607D01*
X779363Y215115D01*
X789846Y213266D01*
X801500Y215321D01*
X801726Y215282D01*
Y215281D01*
X804784Y214741D01*
X808126Y214152D01*
X811274Y211948D01*
X824110Y193614D01*
X846550Y177903D01*
X853456Y176685D01*
X854427Y176650D01*
X865138D01*
X865988Y175800D01*
X877811D01*
X878661Y176650D01*
X879658D01*
X880842Y177834D01*
X882872D01*
G01X658687Y830301D02*
G03X657737Y828007I2294J-2294D01*
G01Y824554D01*
X926858Y440209D01*
X930939Y417063D01*
X928423Y404481D01*
X930889Y392316D01*
X930935Y392041D01*
X930874Y391724D01*
X928439Y379563D01*
X930940Y367059D01*
X928439Y354563D01*
X930940Y342059D01*
X928439Y329563D01*
X930940Y317059D01*
X928439Y304563D01*
X930936Y292074D01*
X928100Y277869D01*
Y263700D01*
G01X930800Y263800D02*
Y277600D01*
X933692Y292061D01*
X931192Y304561D01*
X933692Y317061D01*
X931192Y329561D01*
X933692Y342061D01*
X931192Y354561D01*
X933692Y367061D01*
X931192Y379561D01*
X933692Y392061D01*
X931192Y404561D01*
X933692Y417061D01*
X927357Y448732D01*
X669035Y817659D01*
Y828600D01*
G03X668995Y828978I-1813J-1D01*
G03X668504Y829882I-1773J-378D01*
G01X668085Y830301D01*
G01X655487D02*
G02X656437Y828007I-2294J-2294D01*
G01Y824144D01*
X925627Y439699D01*
X929616Y417078D01*
X927148Y404736D01*
X927102Y404485D01*
X927148Y404225D01*
X928430Y397896D01*
X929610Y392080D01*
X929614Y392057D01*
X929598Y391974D01*
X927113Y379563D01*
X929614Y367059D01*
Y367058D01*
X927113Y354563D01*
X929614Y342058D01*
X927113Y329563D01*
X929614Y317058D01*
X927113Y304563D01*
X929610Y292074D01*
X926800Y277998D01*
Y263700D01*
G01X932100Y263800D02*
Y277471D01*
X935018Y292061D01*
X932518Y304561D01*
X935018Y317061D01*
X932518Y329561D01*
X935018Y342061D01*
X932518Y354561D01*
X935018Y367061D01*
X932518Y379561D01*
X935018Y392061D01*
X932518Y404561D01*
X935018Y417061D01*
X928579Y449255D01*
X670335Y818069D01*
Y828600D01*
G02X670347Y828815I1813J7D01*
G02X670866Y829882I1800J-216D01*
G01X671285Y830301D01*
G01X940000Y263800D02*
Y276684D01*
X943075Y292061D01*
X940575Y304561D01*
X943075Y317061D01*
X940575Y329561D01*
X943075Y342061D01*
X940575Y354561D01*
X943075Y367061D01*
X940575Y379561D01*
X943075Y392061D01*
X940575Y404561D01*
X943075Y417061D01*
X940575Y429561D01*
X943075Y442061D01*
X940000Y457438D01*
X695500Y806620D01*
Y828600D01*
G02X696008Y829828I1736J1D01*
G01X696482Y830301D01*
G01X683884D02*
G03X683000Y828167I2134J-2134D01*
G01Y818514D01*
X936100Y457049D01*
X939098Y442061D01*
X936598Y429561D01*
X939098Y417061D01*
X936598Y404561D01*
X939098Y392061D01*
X936598Y379561D01*
X939098Y367061D01*
X936598Y354561D01*
X939098Y342061D01*
X936598Y329561D01*
X939098Y317061D01*
X936598Y304561D01*
X939098Y292061D01*
X936100Y277073D01*
Y263800D01*
G01X938700D02*
Y276814D01*
X941749Y292061D01*
X939249Y304561D01*
X941749Y317061D01*
X939249Y329561D01*
X941749Y342061D01*
X939249Y354561D01*
X941749Y367061D01*
X939249Y379561D01*
X941749Y392061D01*
X939249Y404561D01*
X941749Y417061D01*
X939249Y429561D01*
X941749Y442061D01*
X938778Y456915D01*
X694200Y806210D01*
Y828600D01*
G03X693646Y829936I-1890J-1D01*
G01X693282Y830301D01*
G01X680684D02*
G02X681700Y827848I-2453J-2453D01*
G01Y818103D01*
X934878Y456526D01*
X937772Y442061D01*
X935272Y429561D01*
X937772Y417061D01*
X935272Y404561D01*
X937772Y392061D01*
X935272Y379561D01*
X937772Y367061D01*
X935272Y354561D01*
X937772Y342061D01*
X935272Y329561D01*
X937772Y317061D01*
X935272Y304561D01*
X937772Y292061D01*
X934800Y277202D01*
Y263800D01*
G01X732500Y98421D02*
G02X734058Y99301I1558J-939D01*
G01X739157D01*
X747594Y104082D01*
X756098Y105610D01*
X774465Y101084D01*
X808452Y111969D01*
X849117Y103837D01*
X859618Y105937D01*
X873805Y103100D01*
X879941D01*
X886933Y107996D01*
X888703Y110524D01*
X888840Y111301D01*
Y114900D01*
G01X720800Y102150D02*
G02X722394Y103100I1594J-862D01*
G01X724709D01*
X726685Y101362D01*
X728923Y95820D01*
X735458Y92596D01*
X741103Y93796D01*
X745424Y96603D01*
X745425D01*
X746226Y97124D01*
X758162Y99661D01*
X775056Y96070D01*
X817086Y105003D01*
X846911Y98661D01*
X860226Y101326D01*
X873367Y98700D01*
X877455Y97980D01*
X881540Y98700D01*
X885669Y102830D01*
X889907Y105797D01*
X892751Y109917D01*
Y113905D01*
G01X720800Y93150D02*
X721219Y93570D01*
G02X722500Y94100I1280J-1281D01*
G01X723400D01*
G02X723979Y93993I0J-1622D01*
G02X724372Y93776I-580J-1515D01*
G02X724543Y93628I-964J-1287D01*
G01X725112Y93059D01*
X726626Y85939D01*
X730046Y83715D01*
X730197Y83747D01*
X739752Y85765D01*
X740125Y85845D01*
X742793Y89948D01*
X747207Y92816D01*
X750333Y93480D01*
X763990Y90577D01*
X816493Y101736D01*
X848085Y95018D01*
X860872Y97273D01*
X872983Y94850D01*
X878588Y93862D01*
X884189Y94850D01*
X885450Y96111D01*
X888020Y99780D01*
X891689Y102350D01*
X893250Y103911D01*
X896355Y108344D01*
X896714Y110386D01*
Y112867D01*
G01X900626Y112428D02*
Y105457D01*
X900315Y103686D01*
X898652Y101313D01*
X888339Y91000D01*
X880917Y89690D01*
X859869Y93400D01*
X848365Y91375D01*
X828492Y95598D01*
X826791Y95237D01*
X824219Y93567D01*
X823386Y92284D01*
X822681Y88962D01*
X821342Y86904D01*
X819525Y85728D01*
X816720Y85131D01*
X812451Y86039D01*
X810027Y87613D01*
X809107Y89030D01*
X808641Y91219D01*
X808034Y92153D01*
X808035D01*
X805723Y93654D01*
X802977Y94237D01*
X794745Y92488D01*
X789156Y88858D01*
X767598Y84275D01*
X765086D01*
X759148Y85537D01*
X728972Y79134D01*
X722028D01*
G03X721038Y78724I0J-1400D01*
G03X720800Y78150I573J-574D01*
G01X887540Y114900D02*
Y111415D01*
X887472Y111034D01*
X885999Y108930D01*
X879531Y104400D01*
X873934D01*
X859618Y107263D01*
X849117Y105163D01*
X808376Y113310D01*
X774419Y102435D01*
X765279Y104687D01*
X765277Y104688D01*
X756140Y106939D01*
X747146Y105323D01*
X738814Y100601D01*
X734058D01*
G02X732500Y101621I0J1700D01*
G01X720800Y105350D02*
G03X721984Y104400I1184J263D01*
G01X725200D01*
X727775Y102135D01*
X729943Y96767D01*
X735629Y93962D01*
X740597Y95018D01*
X745719Y98346D01*
X758162Y100991D01*
X775056Y97400D01*
X817086Y106333D01*
X846919Y99989D01*
X860226Y102652D01*
X873607Y99978D01*
X877452Y99301D01*
X880911Y99911D01*
X884830Y103830D01*
X888970Y106728D01*
X891451Y110323D01*
Y113905D01*
G01X720800Y96350D02*
X721219Y95930D01*
G03X722500Y95400I1280J1281D01*
G01X723400D01*
G02X724444Y95208I2J-2923D01*
G02X725152Y94817I-1045J-2729D01*
G02X725462Y94548I-1747J-2326D01*
G01X726304Y93706D01*
X727786Y86736D01*
X730304Y85099D01*
X739327Y87004D01*
X741853Y90888D01*
Y90889D01*
X746701Y94038D01*
X750333Y94810D01*
X763990Y91907D01*
X816493Y103066D01*
X848108Y96343D01*
X860887Y98596D01*
X873223Y96128D01*
X878588Y95183D01*
X883559Y96060D01*
X883647Y96148D01*
X883650Y96150D01*
X884450Y96950D01*
X887086Y100714D01*
X890850Y103350D01*
X892250Y104750D01*
X895124Y108854D01*
X895414Y110500D01*
Y112867D01*
G01X720800Y81350D02*
G03X720991Y80889I652J0D01*
G03X722089Y80434I1098J1097D01*
G01X728835D01*
X732340Y81178D01*
X732339D01*
X759148Y86867D01*
X765223Y85575D01*
X767461D01*
X788650Y90080D01*
X793805Y93428D01*
X793948Y93648D01*
X802977Y95567D01*
X806229Y94876D01*
X808975Y93093D01*
X809863Y91726D01*
X810329Y89536D01*
X810967Y88553D01*
X812957Y87261D01*
X816720Y86461D01*
X819020Y86950D01*
X820403Y87845D01*
X821459Y89468D01*
X822164Y92790D01*
X823279Y94507D01*
X826285Y96459D01*
X828492Y96928D01*
X848388Y92700D01*
X859869Y94721D01*
X880917Y91011D01*
X887709Y92210D01*
X897652Y102153D01*
X899084Y104196D01*
X899326Y105571D01*
Y112428D01*
G01X720800Y114150D02*
G02X722394Y115100I1594J-862D01*
G01X725388D01*
X727531Y114721D01*
X737792Y116529D01*
X754072Y113658D01*
X763700Y108400D01*
X767000Y107500D01*
X776400Y110200D01*
X782784Y108107D01*
X808052Y116224D01*
X849072Y108020D01*
X860100Y110226D01*
X874233Y107400D01*
X878003D01*
G03X881244Y108742I0J4585D01*
G01X883165Y110664D01*
G03X884242Y112535I-2936J2936D01*
G03X884380Y113593I-3987J1058D01*
G01Y116265D01*
G02X884548Y116795I920J0D01*
G02X886221Y116265I753J-530D01*
G01Y116142D01*
G01X720800Y117350D02*
G03X722394Y116400I1594J862D01*
G01X725503D01*
X727531Y116042D01*
X737792Y117850D01*
X754508Y114902D01*
X764190Y109615D01*
X765591Y109232D01*
X766991Y108850D01*
X776425Y111560D01*
X782788Y109474D01*
X807976Y117566D01*
X849072Y109346D01*
X854331Y110398D01*
X860100Y111552D01*
X874362Y108700D01*
X878002D01*
G03X880324Y109662I0J3284D01*
G01X882245Y111584D01*
G03X882985Y112869I-2016J2016D01*
G03X883080Y113600I-2756J730D01*
G01Y116265D01*
G02X883485Y117544I2221J0D01*
G01X885286Y119345D01*
X886221Y120079D01*
G01X951800Y263600D02*
Y300514D01*
X957609Y329561D01*
X952609Y354561D01*
X957609Y379561D01*
X952609Y404561D01*
X957609Y429561D01*
X951800Y458608D01*
X734273Y769269D01*
X727028Y810353D01*
Y828007D01*
G02X727978Y830301I3244J0D01*
G01X950500Y263600D02*
Y300644D01*
X956283Y329561D01*
X951283Y354561D01*
X956283Y379561D01*
X951283Y404561D01*
X956283Y429561D01*
X950578Y458085D01*
X733042Y768759D01*
X725728Y810237D01*
Y828007D01*
G03X724778Y830301I-3244J0D01*
G01X954400Y263500D02*
Y300255D01*
X960261Y329561D01*
X955261Y354561D01*
X960261Y379561D01*
X955261Y404561D01*
X960261Y429561D01*
X954478Y458473D01*
X750465Y749833D01*
X738327Y818678D01*
Y828007D01*
G03X737377Y830301I-3244J0D01*
G01X959700Y263800D02*
Y299728D01*
X965667Y329561D01*
X960667Y354561D01*
X965667Y379561D01*
X960667Y404561D01*
X965929Y430873D01*
X960000Y464500D01*
X764835Y743225D01*
X752225Y814737D01*
Y828007D01*
G02X753175Y830301I3244J0D01*
G01X955700Y263500D02*
Y300126D01*
X961587Y329561D01*
X956587Y354561D01*
X961587Y379561D01*
X956587Y404561D01*
X961587Y429561D01*
X955700Y458996D01*
X751696Y750343D01*
X739627Y818795D01*
Y828007D01*
G02X740577Y830301I3244J0D01*
G01X958400Y263800D02*
Y299857D01*
X964341Y329561D01*
X959341Y354561D01*
X964341Y379561D01*
X959341Y404561D01*
X964606Y430888D01*
X961687Y447440D01*
X958769Y463990D01*
X763604Y742715D01*
X750925Y814623D01*
Y828007D01*
G03X749975Y830301I-3244J0D01*
G01X963600Y263600D02*
Y299339D01*
X969644Y329561D01*
X964644Y354561D01*
X969644Y379561D01*
X964644Y404561D01*
X971280Y437741D01*
X966025Y467544D01*
X777030Y737452D01*
X764824Y806677D01*
Y828007D01*
G02X765774Y830301I3244J0D01*
G01X962300Y263600D02*
Y299469D01*
X968318Y329561D01*
X963318Y354561D01*
X968318Y379561D01*
X963318Y404561D01*
X969957Y437756D01*
X967376Y452395D01*
X964794Y467034D01*
X775799Y736942D01*
X763524Y806563D01*
Y828007D01*
G03X762574Y830301I-3244J0D01*
G01X971400Y263700D02*
Y298563D01*
X977600Y329561D01*
X972600Y354561D01*
X977600Y379561D01*
X972600Y404561D01*
X980071Y441918D01*
X974452Y473785D01*
X802567Y719262D01*
X800585Y730501D01*
X792020Y779100D01*
X795000Y796000D01*
X790020Y824246D01*
Y828007D01*
G02X790970Y830301I3244J0D01*
G01X967500Y263800D02*
Y298951D01*
X973622Y329561D01*
X968622Y354561D01*
X973622Y379561D01*
X968622Y404561D01*
X975533Y439118D01*
X970000Y470500D01*
X791154Y725918D01*
X776562Y808679D01*
X777422Y813558D01*
Y828007D01*
G02X778372Y830301I3244J0D01*
G01X970100Y263700D02*
Y298693D01*
X976274Y329561D01*
X971274Y354561D01*
X976274Y379561D01*
X971274Y404561D01*
X978748Y441933D01*
X973221Y473275D01*
X801336Y718752D01*
X799329Y730135D01*
X790699Y779100D01*
X793679Y796000D01*
X788720Y824129D01*
Y828007D01*
G03X787770Y830301I-3244J0D01*
G01X966200Y263800D02*
Y299081D01*
X972296Y329561D01*
X967296Y354561D01*
X972296Y379561D01*
X967296Y404561D01*
X974210Y439133D01*
X968769Y469990D01*
X789923Y725408D01*
X775241Y808679D01*
X776122Y813675D01*
Y828007D01*
G03X775172Y830301I-3244J0D01*
G01X975400Y263600D02*
Y298165D01*
X981679Y329561D01*
X976679Y354561D01*
X981679Y379561D01*
X976679Y404561D01*
X984406Y443194D01*
X978422Y477120D01*
X814989Y710529D01*
X803076Y778089D01*
X806130Y795410D01*
X802619Y815325D01*
Y828007D01*
G02X803569Y830301I3244J0D01*
G01X974100Y263600D02*
Y298295D01*
X980353Y329561D01*
X975353Y354561D01*
X980353Y379561D01*
X975353Y404561D01*
X983083Y443209D01*
X977191Y476610D01*
X813758Y710019D01*
X801755Y778089D01*
X804809Y795410D01*
X801319Y815208D01*
Y828007D01*
G03X800369Y830301I-3244J0D01*
G01X853962D02*
G03X853012Y828007I2294J-2294D01*
G01Y822231D01*
X837972Y800752D01*
X829569Y753101D01*
X835762Y717981D01*
X995791Y489437D01*
X1010710Y404822D01*
Y402841D01*
X991200Y292237D01*
Y263994D01*
G01X987200Y264430D02*
Y298048D01*
X1005453Y401521D01*
Y403487D01*
X991335Y483558D01*
X829165Y715161D01*
X822739Y751601D01*
X833402Y812077D01*
X840414Y822091D01*
Y828007D01*
G02X841364Y830301I3244J0D01*
G01X979300Y263500D02*
Y297777D01*
X985657Y329561D01*
X980657Y354561D01*
X985657Y379561D01*
X980657Y404561D01*
X988612Y444337D01*
X982217Y480604D01*
X823782Y706875D01*
X811461Y776749D01*
X817500Y811000D01*
X815217Y823947D01*
Y828007D01*
G02X816167Y830301I3244J0D01*
G01X850762D02*
G02X851712Y828007I-2294J-2294D01*
G01Y822642D01*
X836741Y801262D01*
X828248Y753101D01*
X834531Y717472D01*
X994560Y488927D01*
X1009410Y404708D01*
Y402955D01*
X989900Y292351D01*
Y264288D01*
G01X985900Y264136D02*
Y298162D01*
X1004153Y401635D01*
Y403373D01*
X990104Y483048D01*
X827934Y714652D01*
X821418Y751601D01*
X832171Y812587D01*
X839114Y822502D01*
Y828007D01*
G03X838164Y830301I-3244J0D01*
G01X978000Y263500D02*
Y297907D01*
X984331Y329561D01*
X979331Y354561D01*
X984331Y379561D01*
X979331Y404561D01*
X987289Y444352D01*
X980985Y480095D01*
X822551Y706365D01*
X810140Y776749D01*
X816179Y811000D01*
X813917Y823830D01*
Y828007D01*
G03X812967Y830301I-3244J0D01*
G01X1057000Y54500D02*
G02X1058353Y55241I1353J-865D01*
G01X1059932D01*
X1061226Y56237D01*
X1061622Y59020D01*
X1058839Y63311D01*
X1054306Y66255D01*
X1019662Y73618D01*
X1010435Y79610D01*
X992470Y89574D01*
X991173Y96933D01*
Y111771D01*
G01X994800Y110710D02*
Y100943D01*
X1001621Y91198D01*
X1007868Y86824D01*
X1026674Y82829D01*
X1027504Y83368D01*
X1029118Y83025D01*
X1029657Y82195D01*
X1031271Y81852D01*
X1032101Y82391D01*
X1033715Y82048D01*
X1034254Y81218D01*
X1035868Y80875D01*
X1036698Y81414D01*
X1038312Y81071D01*
X1038851Y80241D01*
X1040465Y79898D01*
X1055225Y83035D01*
X1060477Y81918D01*
X1065007Y78976D01*
X1066603Y76519D01*
X1067579Y71928D01*
X1065728Y63226D01*
X1066284Y60611D01*
G03X1066564Y60381I907J818D01*
G01X1068308Y59331D01*
X1070037D01*
G03X1071135Y60375I0J1099D01*
G01X998500Y114300D02*
Y103355D01*
X1002895Y97077D01*
X1012852Y90106D01*
X1025170Y87489D01*
X1037994Y90215D01*
X1072531Y82874D01*
X1082451Y84983D01*
X1101762Y97526D01*
X1110558Y110090D01*
X1112350Y120251D01*
X1111782Y121062D01*
X1112068Y122687D01*
X1112879Y123255D01*
X1113876Y128906D01*
X1114627Y129978D01*
X1118084Y132400D01*
X1120074D01*
G03X1121786Y133109I0J2421D01*
G01X1122001Y133324D01*
G01X1003318Y117450D02*
Y105413D01*
X1003735Y103051D01*
X1006160Y99587D01*
X1014222Y93943D01*
X1025675Y91509D01*
X1039111Y94365D01*
X1073142Y87132D01*
X1077890Y88141D01*
X1096480Y100213D01*
X1103806Y111496D01*
X1106509Y126797D01*
X1111366Y133733D01*
X1120370Y140041D01*
X1136083Y142800D01*
X1137288D01*
G02X1140125Y141626I1J-4012D01*
G02X1140900Y139751I-1875J-1872D01*
G01Y139600D01*
G03X1141430Y138322I1808J1D01*
G01X1141900Y137851D01*
G01X1007618Y111060D02*
Y107665D01*
X1008120Y104857D01*
X1010409Y101586D01*
X1013875Y99159D01*
X1028980Y96496D01*
X1041500Y99000D01*
X1054000Y96500D01*
X1058467Y95712D01*
X1086706Y100692D01*
X1093229Y105259D01*
X1100473Y115604D01*
X1102800Y128800D01*
X1108497Y136937D01*
X1120894Y145618D01*
X1133364Y147816D01*
X1157780Y143509D01*
X1157782Y143507D01*
G02X1160307Y140254I-833J-3253D01*
G03X1160837Y138976I1808J1D01*
G01X1161307Y138505D01*
G01X1057000Y57700D02*
G03X1058159Y56541I1159J0D01*
G01X1059487D01*
X1060013Y56946D01*
X1060266Y58721D01*
X1057899Y62371D01*
X1053800Y65033D01*
X1019156Y72396D01*
X1009765Y78495D01*
X991297Y88738D01*
X989873Y96818D01*
Y111648D01*
G01X1071135Y57175D02*
G03X1069699Y58031I-1436J-776D01*
G01X1067947D01*
X1065893Y59266D01*
G02X1065076Y60057I1301J2161D01*
G01X1065071Y60064D01*
X1064398Y63226D01*
X1066249Y71928D01*
X1065381Y76013D01*
X1064067Y78036D01*
X1059971Y80696D01*
X1055225Y81705D01*
X1040465Y78568D01*
X1007339Y85607D01*
X1000687Y90264D01*
X993500Y100533D01*
Y110710D01*
G01X997200Y114300D02*
Y102945D01*
X1001961Y96143D01*
X1012323Y88889D01*
X1025170Y86159D01*
X1037994Y88885D01*
X1072531Y81544D01*
X1082957Y83761D01*
X1102682Y96573D01*
X1111789Y109580D01*
X1115107Y128396D01*
X1115561Y129044D01*
X1118495Y131100D01*
X1120490D01*
G02X1122001Y130124I0J-1658D01*
G01X1002018Y117500D02*
Y105206D01*
X1002037Y105187D01*
X1002504Y102541D01*
X1005226Y98653D01*
X1013693Y92726D01*
X1025675Y90179D01*
X1039111Y93035D01*
X1073142Y85802D01*
X1078396Y86919D01*
X1097420Y99273D01*
X1105041Y111009D01*
X1107740Y126287D01*
X1112300Y132800D01*
X1120880Y138810D01*
X1136197Y141500D01*
X1137288D01*
G02X1139205Y140706I0J-2711D01*
G02X1139600Y139752I-954J-954D01*
G01Y139600D01*
G02X1139000Y138150I-2050J-1D01*
G01X1138700Y137851D01*
G01X1158107Y138505D02*
X1158407Y138804D01*
G03X1159007Y140254I-1450J1449D01*
G01X1159006D01*
G03X1157484Y142240I-2057J0D01*
G01X1133364Y146495D01*
X1121404Y144387D01*
X1109431Y136003D01*
X1104031Y128290D01*
X1101704Y115094D01*
X1094163Y104325D01*
X1087216Y99461D01*
X1058467Y94391D01*
X1053775Y95219D01*
X1041500Y97674D01*
X1029000Y95174D01*
X1028994Y95173D01*
X1021201Y96547D01*
X1013365Y97928D01*
X1009475Y100652D01*
X1006890Y104346D01*
X1006318Y107549D01*
Y111060D01*
G01X1006900Y263500D02*
Y269095D01*
X1007716Y273725D01*
X1102887Y698505D01*
X1101762Y703358D01*
X1082015Y803856D01*
X1081359Y807572D01*
Y828007D01*
G02X1082309Y830301I3244J0D01*
G01X1003000Y263300D02*
Y267285D01*
X1078276Y694208D01*
X1062251Y785087D01*
X1068869Y822632D01*
Y828275D01*
G02X1069706Y830296I2858J0D01*
G01X1069711Y830301D01*
G01X999150Y263450D02*
Y271501D01*
X1064182Y640315D01*
X1044751Y750447D01*
X1056007Y814291D01*
X1055000Y820000D01*
X1056162Y826594D01*
Y828800D01*
G02X1056552Y829740I1330J-1D01*
G01X1057112Y830301D01*
G01X995100Y263600D02*
Y267285D01*
X1059139Y630490D01*
X1037890Y751001D01*
X1042655Y778025D01*
X1047500Y805500D01*
X1045639Y816053D01*
X1044515Y817659D01*
X1043700Y818823D01*
Y828336D01*
G02X1044514Y830301I2779J0D01*
G01X1005600Y263500D02*
Y269212D01*
X1006440Y273980D01*
X1101553Y698500D01*
X1100490Y703086D01*
X1080736Y803618D01*
X1080059Y807458D01*
Y828007D01*
G03X1079109Y830301I-3244J0D01*
G01X1001700Y263300D02*
Y267399D01*
X1076955Y694208D01*
X1060930Y785087D01*
X1067569Y822746D01*
Y828400D01*
G03X1066973Y829839I-2035J0D01*
G01X1066511Y830301D01*
G01X997850Y263694D02*
Y271615D01*
X1062861Y640315D01*
X1043430Y750447D01*
X1054686Y814291D01*
X1054222Y816920D01*
X1054043Y817935D01*
X1053679Y820000D01*
X1054862Y826710D01*
Y828800D01*
G03X1054472Y829740I-1330J-1D01*
G01X1053912Y830301D01*
G01X993800Y263600D02*
Y267399D01*
X1057818Y630490D01*
X1036569Y751001D01*
X1046179Y805500D01*
X1045293Y810523D01*
X1044408Y815543D01*
X1043450Y816913D01*
X1042400Y818413D01*
Y828337D01*
G03X1041779Y829836I-2120J0D01*
G01X1041314Y830301D01*
G01X1182061Y142478D02*
X1181794Y142745D01*
G02X1181150Y144300I1555J1555D01*
G01Y145496D01*
X1179568Y147078D01*
X1173971Y148783D01*
X1171231Y147922D01*
X1168873Y147181D01*
X1164461Y145795D01*
X1160547Y146485D01*
X1133147Y151317D01*
X1119547Y148920D01*
X1106132Y139528D01*
X1097500Y127200D01*
X1095707Y117032D01*
X1090687Y109863D01*
X1084600Y105600D01*
X1060521Y101354D01*
X1042014Y104618D01*
X1026600Y101900D01*
X1015694Y103823D01*
X1013006Y105704D01*
X1011842Y107366D01*
X1011600Y108737D01*
Y111530D01*
G01X1178861Y142478D02*
X1179261Y142878D01*
G03X1179850Y144300I-1422J1422D01*
G01Y144957D01*
X1178878Y145929D01*
X1173977Y147422D01*
X1164548Y144459D01*
X1148579Y147275D01*
X1133147Y149996D01*
X1120056Y147689D01*
X1107066Y138594D01*
X1098731Y126690D01*
X1096938Y116522D01*
X1091621Y108929D01*
X1085110Y104369D01*
X1060521Y100033D01*
X1042014Y103297D01*
X1026600Y100579D01*
X1015184Y102592D01*
X1012073Y104770D01*
X1010611Y106856D01*
X1010300Y108623D01*
Y111530D01*
G01X1234209Y142463D02*
X1233680Y142993D01*
G02X1233160Y144247I1252J1254D01*
G01Y145622D01*
X1226633Y154947D01*
X1217093Y161626D01*
X1212810Y167743D01*
X1205541Y172833D01*
X1193113Y175024D01*
X1185659Y173710D01*
X1163859Y178070D01*
X1148104Y174919D01*
X1144569Y175626D01*
X1108313Y168376D01*
X1089897Y155482D01*
X1089765Y155294D01*
X1089766D01*
X1086785Y151036D01*
X1085360Y149001D01*
X1083935Y146967D01*
X1072156Y138719D01*
X1054345Y135578D01*
X1034580Y138739D01*
X1024703D01*
G01X1190835Y137899D02*
X1190563Y138171D01*
G02X1189800Y140013I1842J1842D01*
G01Y142071D01*
X1190205Y144388D01*
X1192393Y147513D01*
X1192725Y149398D01*
X1192339Y151587D01*
X1192172Y151826D01*
Y151825D01*
X1191399Y152928D01*
X1184324Y157884D01*
X1167465Y160858D01*
X1118234Y152182D01*
X1103221Y141670D01*
X1095672Y130889D01*
X1078691Y118999D01*
X1045812Y113200D01*
X1018874D01*
G01X1199400Y142851D02*
G02X1198450Y145914I4463J3063D01*
G01Y147327D01*
X1197656Y150297D01*
X1194423Y156755D01*
X1187578Y161550D01*
X1169595Y164859D01*
X1150119Y161426D01*
X1146550Y162055D01*
X1114425Y155767D01*
X1114422Y155766D01*
X1101152Y146473D01*
X1092545Y134182D01*
X1076871Y123206D01*
X1055480Y119434D01*
X1044693Y121336D01*
X1044125Y122147D01*
X1042500Y122433D01*
X1041689Y121866D01*
X1040064Y122152D01*
X1039496Y122963D01*
X1037871Y123250D01*
X1037060Y122682D01*
X1031762Y123616D01*
X1022077D01*
X1021028Y122567D01*
Y121029D01*
X1020078Y120079D01*
G01X1206991Y156730D02*
X1206041Y157680D01*
Y159577D01*
X1203666Y161953D01*
X1200364Y163586D01*
X1167662Y169647D01*
X1151142Y165863D01*
X1146764Y166635D01*
X1112125Y159707D01*
X1096772Y148957D01*
X1091036Y140765D01*
X1076723Y130744D01*
X1053971Y126732D01*
X1029884Y130978D01*
X1024893D01*
G01X1225348Y137960D02*
X1224975Y138333D01*
G02X1224400Y139721I1388J1388D01*
G01Y141885D01*
X1224218Y142912D01*
X1224007Y144109D01*
X1219196Y150979D01*
X1214646Y154165D01*
X1212555Y160972D01*
X1210081Y164209D01*
X1209225Y164733D01*
X1208379Y165251D01*
X1165404Y173846D01*
X1149225Y170610D01*
X1146646Y171126D01*
X1110678Y163933D01*
X1093354Y151802D01*
X1088255Y144520D01*
X1073257Y134018D01*
X1054561Y130722D01*
X1031589Y134772D01*
X1021533D01*
G01X1231009Y142463D02*
G03X1231860Y144517I-2054J2054D01*
G01Y145212D01*
X1225699Y154013D01*
X1216159Y160692D01*
X1211876Y166809D01*
X1205031Y171602D01*
X1193113Y173703D01*
X1185644Y172387D01*
X1163859Y176744D01*
X1148104Y173593D01*
X1144569Y174300D01*
X1108836Y167154D01*
X1090831Y154548D01*
X1086425Y148255D01*
X1085713Y147238D01*
X1084868Y146033D01*
X1072666Y137488D01*
X1054356Y134259D01*
X1034476Y137439D01*
X1024703D01*
G01X1239700Y137851D02*
G03X1240650Y140145I-2294J2294D01*
G01Y141902D01*
X1240167Y144637D01*
X1235680Y151046D01*
X1220407Y161740D01*
X1214216Y170580D01*
X1205149Y176928D01*
X1193042Y179350D01*
X1181475Y177036D01*
X1162662Y180799D01*
X1149229Y178113D01*
X1143042Y179350D01*
X1126563Y176054D01*
Y176053D01*
X1110089Y172759D01*
X1086853Y156489D01*
X1082077Y149668D01*
X1071510Y142269D01*
X1053253Y139051D01*
X1040089Y141372D01*
X1023000D01*
G01X1187635Y137899D02*
G03X1188500Y139987I-2088J2088D01*
G01Y142184D01*
X1188974Y144897D01*
X1191162Y148023D01*
X1191404Y149398D01*
X1191108Y151078D01*
X1190466Y151994D01*
X1183814Y156653D01*
X1167465Y159537D01*
X1118744Y150951D01*
X1104155Y140736D01*
X1096606Y129955D01*
X1079201Y117768D01*
X1045926Y111900D01*
X1018800D01*
G01X1196200Y142851D02*
G03X1197150Y145914I-4463J3063D01*
G01Y147156D01*
X1196434Y149833D01*
X1193407Y155878D01*
X1187064Y160322D01*
X1169590Y163538D01*
X1150119Y160105D01*
X1146562Y160732D01*
X1114945Y154544D01*
X1102086Y145539D01*
X1093479Y133248D01*
X1077381Y121975D01*
X1055480Y118113D01*
X1031648Y122316D01*
X1022616D01*
X1022328Y122028D01*
Y121029D01*
X1023278Y120079D01*
G01X1024893Y129678D02*
X1029770D01*
X1053971Y125411D01*
X1077233Y129513D01*
X1091970Y139831D01*
X1097706Y148023D01*
X1112648Y158485D01*
X1146779Y165312D01*
X1151176Y164536D01*
X1167690Y168319D01*
X1183822Y165329D01*
X1199949Y162340D01*
X1202897Y160882D01*
X1204741Y159038D01*
Y157680D01*
X1203791Y156730D01*
G01X1222148Y137960D02*
G03X1223100Y140258I-2298J2298D01*
G01Y141769D01*
X1223099Y141770D01*
X1222776Y143599D01*
X1218262Y150045D01*
X1213534Y153356D01*
X1211380Y160367D01*
X1209195Y163227D01*
X1207897Y164021D01*
X1165404Y172520D01*
X1149225Y169284D01*
X1146646Y169800D01*
X1111201Y162711D01*
X1094288Y150868D01*
X1089189Y143586D01*
X1073767Y132787D01*
X1054561Y129401D01*
X1031475Y133472D01*
X1021600D01*
G01X1242900Y137851D02*
X1242602Y138149D01*
G02X1241950Y139723I1574J1574D01*
G01Y142016D01*
X1241398Y145147D01*
X1236614Y151980D01*
X1221341Y162674D01*
X1215150Y171514D01*
X1205672Y178150D01*
X1193042Y180676D01*
X1181475Y178362D01*
X1162662Y182125D01*
X1149229Y179439D01*
X1143042Y180676D01*
X1109566Y173981D01*
X1085919Y157423D01*
X1081143Y150602D01*
X1071000Y143500D01*
X1053253Y140372D01*
X1040203Y142672D01*
X1023100D01*
G01X1020078Y147638D02*
G03X1019156Y147256I0J-1304D01*
G01X1019144Y147244D01*
G03X1018759Y146314I931J-930D01*
G01Y146158D01*
G03X1019034Y145494I939J0D01*
G03X1019424Y145260I664J664D01*
G03X1019698Y145219I274J898D01*
G01X1020614D01*
G03X1021580Y145620I-1J1366D01*
G01X1021629Y145670D01*
G02X1024600Y146900I2970J-2971D01*
G01X1040405D01*
X1052167Y144828D01*
X1067144Y147469D01*
X1078256Y155249D01*
X1082321Y161053D01*
X1108453Y179351D01*
X1141845Y185240D01*
X1149367Y183736D01*
X1161867Y186236D01*
X1178665Y182876D01*
X1191165Y185376D01*
X1207486Y182112D01*
X1217500Y175100D01*
X1223440Y166618D01*
X1234326Y159000D01*
X1250819Y156088D01*
X1259218Y150634D01*
X1260953Y148899D01*
Y147351D01*
G03X1261944Y145770I1757J0D01*
G01X1277265Y137673D02*
X1276925Y138013D01*
G02X1276258Y139623I1610J1610D01*
G01Y141815D01*
X1263476Y154597D01*
X1258190Y158031D01*
X1236359Y161881D01*
X1226802Y168572D01*
X1220200Y178000D01*
X1209258Y185662D01*
X1188938Y189726D01*
X1176438Y187226D01*
X1161538Y190206D01*
X1149038Y187706D01*
X1139691Y189575D01*
X1106261Y183681D01*
X1079798Y165150D01*
X1074791Y157999D01*
X1064950Y151109D01*
X1051400Y148721D01*
X1041197Y150519D01*
X1022580D01*
G01X1020078Y155512D02*
G03X1019156Y155130I0J-1304D01*
G01X1019144Y155118D01*
G03X1018759Y154188I931J-930D01*
G01Y154032D01*
G03X1019034Y153368I939J0D01*
G03X1019424Y153134I664J664D01*
G03X1019698Y153093I274J898D01*
G01X1020100D01*
G03X1020702Y153343I-1J852D01*
G01X1023007Y155648D01*
X1038300D01*
X1051551Y153311D01*
X1063400Y155400D01*
X1071607Y161147D01*
X1077534Y169612D01*
X1103941Y188101D01*
X1137871Y194084D01*
X1149411Y191776D01*
X1161911Y194276D01*
X1174411Y191776D01*
X1186911Y194276D01*
X1211568Y189345D01*
X1223200Y181200D01*
X1228940Y173002D01*
X1241649Y164103D01*
X1268418Y159383D01*
G02X1269158Y159077I-320J-1821D01*
G01X1282738Y149564D01*
X1285488Y145331D01*
Y143750D01*
G03X1286276Y141849I2689J1D01*
G01X1286543Y141581D01*
G01X1296017Y137478D02*
X1295861Y137634D01*
G02X1295149Y139353I1719J1719D01*
G01Y143087D01*
X1288041Y150195D01*
X1271034Y162103D01*
X1245913Y166532D01*
X1233292Y175369D01*
X1227666Y183403D01*
X1214659Y192511D01*
X1184584Y198526D01*
X1172084Y196026D01*
X1159584Y198526D01*
X1147084Y196026D01*
X1135605Y198322D01*
X1102392Y192466D01*
X1073472Y172217D01*
X1067930Y164301D01*
X1061338Y159685D01*
X1050635Y157798D01*
X1036600Y160273D01*
X1021800D01*
G01X1350025Y830301D02*
X1349535Y829812D01*
G03X1349075Y828700I1112J-1111D01*
G01Y819019D01*
X1208721Y618571D01*
X1157025Y325477D01*
X1119946Y236346D01*
X1088871Y191965D01*
X1073210Y181000D01*
X1057500Y170000D01*
X1038078Y166575D01*
X1026031Y168700D01*
X1023192D01*
G01X1022500Y172600D02*
X1024486D01*
X1037778Y170255D01*
X1055190Y173325D01*
X1071364Y184651D01*
X1087488Y195941D01*
X1117904Y239380D01*
X1152593Y322766D01*
X1204950Y619699D01*
X1336477Y807539D01*
Y828007D01*
G02X1337427Y830301I3244J0D01*
G01X1023192Y176574D02*
X1026031D01*
X1037680Y174520D01*
X1055158Y177602D01*
X1070457Y188315D01*
X1085706Y198992D01*
X1115501Y241546D01*
X1148488Y320842D01*
X1201016Y620248D01*
X1322128Y793214D01*
X1323019Y798267D01*
X1323860Y803036D01*
Y803035D01*
X1323879Y803143D01*
Y828007D01*
G02X1324829Y830301I3244J0D01*
G01X1016141Y147638D02*
G02X1017030Y147270I0J-1258D01*
G01X1017191Y147109D01*
G02X1017459Y146462I-647J-647D01*
G01Y146100D01*
X1017460D01*
G03X1018114Y144574I2239J56D01*
G03X1019044Y144016I1583J1584D01*
G03X1019695Y143919I651J2135D01*
G01X1020614D01*
G03X1022500Y144700I0J2667D01*
G01X1022552Y144751D01*
G02X1024600Y145600I2049J-2048D01*
G01X1040291D01*
X1052165Y143507D01*
X1067654Y146238D01*
X1079190Y154315D01*
X1083255Y160119D01*
X1108963Y178120D01*
X1141830Y183917D01*
X1149367Y182410D01*
X1161867Y184910D01*
X1178665Y181550D01*
X1191165Y184050D01*
X1206963Y180890D01*
X1216566Y174166D01*
X1222507Y165684D01*
X1233816Y157769D01*
X1250332Y154853D01*
X1258395Y149618D01*
X1259653Y148360D01*
Y147351D01*
G02X1258744Y145770I-1829J0D01*
G01X1274065Y137673D02*
X1274211Y137818D01*
G03X1274958Y139623I-1805J1804D01*
G01Y141276D01*
X1262653Y153581D01*
X1257703Y156796D01*
X1235849Y160650D01*
X1225868Y167638D01*
X1219266Y177066D01*
X1208735Y184440D01*
X1188938Y188400D01*
X1176438Y185900D01*
X1161538Y188880D01*
X1149038Y186380D01*
X1139676Y188252D01*
X1106771Y182450D01*
X1080732Y164216D01*
X1075725Y157065D01*
X1065462Y149879D01*
X1051400Y147400D01*
X1041083Y149219D01*
X1022719D01*
G01X1283343Y141581D02*
G03X1284188Y143621I-2040J2040D01*
G01Y144945D01*
X1281785Y148644D01*
X1268412Y158011D01*
G03X1268193Y158102I-315J-449D01*
G01X1241139Y162872D01*
X1228006Y172068D01*
X1222266Y180266D01*
X1211045Y188123D01*
X1186911Y192950D01*
X1174411Y190450D01*
X1161911Y192950D01*
X1149411Y190450D01*
X1137856Y192761D01*
X1104451Y186870D01*
X1078468Y168678D01*
X1072541Y160213D01*
X1063910Y154169D01*
X1051551Y151990D01*
X1038186Y154348D01*
X1023546D01*
X1021620Y152422D01*
G02X1020101Y151793I-1520J1523D01*
G01X1019695D01*
G02X1019044Y151890I0J2232D01*
G02X1018114Y152448I653J2142D01*
G02X1017460Y153974I1585J1582D01*
G01X1017459D01*
Y154336D01*
G03X1017191Y154983I-915J0D01*
G01X1017030Y155144D01*
G03X1016141Y155512I-889J-890D01*
G01X1021800Y158973D02*
X1036486D01*
X1050635Y156477D01*
X1061848Y158454D01*
X1068864Y163367D01*
X1074406Y171283D01*
X1102902Y191235D01*
X1135590Y196999D01*
X1147084Y194700D01*
X1159584Y197200D01*
X1172084Y194700D01*
X1184584Y197200D01*
X1214136Y191289D01*
X1226732Y182469D01*
X1232358Y174435D01*
X1245403Y165301D01*
X1270524Y160872D01*
X1287202Y149195D01*
X1293849Y142548D01*
Y139353D01*
G02X1293253Y137914I-2035J0D01*
G01X1292817Y137478D01*
G01X1346825Y830301D02*
X1347315Y829812D01*
G02X1347775Y828700I-1112J-1111D01*
G01Y819429D01*
X1207490Y619081D01*
X1155769Y325844D01*
X1118800Y236976D01*
X1087937Y192899D01*
X1056990Y171231D01*
X1038078Y167896D01*
X1026145Y170000D01*
X1023731D01*
G01X1022600Y173900D02*
X1024600D01*
X1037778Y171576D01*
X1054680Y174556D01*
X1086554Y196875D01*
X1116758Y240010D01*
X1151337Y323133D01*
X1203719Y620209D01*
X1335177Y807949D01*
Y828007D01*
G03X1334227Y830301I-3244J0D01*
G01X1023731Y177874D02*
X1026145D01*
X1037680Y175841D01*
X1054648Y178833D01*
X1084772Y199926D01*
X1114355Y242176D01*
X1147232Y321208D01*
X1199785Y620757D01*
X1320897Y793724D01*
X1322579Y803261D01*
Y828007D01*
G03X1321629Y830301I-3244J0D01*
G01X1022600Y180474D02*
X1024483D01*
X1037616Y178159D01*
X1050338Y180402D01*
X1084744Y204494D01*
X1114407Y246859D01*
X1142357Y314047D01*
X1169440Y468456D01*
X1196523Y622866D01*
Y622867D01*
X1311046Y786425D01*
X1311047D01*
X1311281Y786759D01*
X1311439Y787254D01*
X1311417Y787294D01*
X1312682Y791288D01*
X1310000Y806500D01*
X1312213Y819051D01*
X1311281Y824337D01*
Y828007D01*
G02X1312231Y830301I3244J0D01*
G01X1020078Y183071D02*
X1019129Y184020D01*
G02X1018760Y184911I891J891D01*
G02X1019007Y185507I843J0D01*
G01X1019500Y186000D01*
G02X1020609Y186497I1207J-1207D01*
G01X1036805Y183641D01*
G03X1037445I320J1823D01*
G01X1050282Y185903D01*
G03X1051022Y186209I-320J1822D01*
G01X1080206Y206644D01*
G03X1080660Y207098I-1061J1515D01*
G01X1112776Y252965D01*
X1129344Y292792D01*
X1186393Y616075D01*
X1277712Y746491D01*
X1285035Y788024D01*
X1287460Y801775D01*
X1287461D01*
X1287500Y802000D01*
X1284751Y817590D01*
X1286083Y825145D01*
Y828007D01*
G02X1287033Y830301I3244J0D01*
G01X1274435D02*
G03X1273485Y828007I2294J-2294D01*
G01Y825586D01*
X1271442Y814000D01*
X1275422Y791429D01*
X1267500Y746500D01*
X1173577Y612364D01*
X1111874Y262450D01*
X1074953Y209722D01*
X1047500Y190500D01*
X1041050Y189363D01*
X1024486Y192284D01*
X1022600D01*
G01X1023192Y196258D02*
X1026031D01*
X1040136Y193771D01*
X1046175Y194836D01*
X1059533Y204190D01*
X1072843Y213509D01*
X1090252Y238373D01*
X1107697Y263286D01*
X1171341Y624224D01*
X1263334Y755605D01*
X1268924Y787308D01*
X1268020Y792440D01*
X1267443Y795711D01*
X1267154Y797348D01*
X1266448Y801351D01*
X1265657Y805837D01*
X1260491Y813211D01*
X1259540Y818609D01*
X1260887Y826245D01*
Y828007D01*
G02X1261837Y830301I3244J0D01*
G01X1249239D02*
G03X1248288Y828007I2293J-2295D01*
G01X1248289D01*
Y826781D01*
X1248927Y823159D01*
X1247816Y816858D01*
X1247407Y814533D01*
X1251392Y791932D01*
X1246584Y764662D01*
X1170255Y655650D01*
X1100908Y262364D01*
X1069194Y217073D01*
X1045288Y200209D01*
X1042852Y198503D01*
X1042758Y198437D01*
X1042679Y198382D01*
X1027797Y200158D01*
X1022600D01*
G01X1023192Y208069D02*
X1026617D01*
X1038008Y206060D01*
X1046089Y207485D01*
X1055828Y214305D01*
X1065518Y221089D01*
X1093383Y260883D01*
X1163973Y661220D01*
X1228317Y753107D01*
X1236482Y799411D01*
X1233821Y814500D01*
X1235690Y825105D01*
Y828007D01*
G02X1236640Y830301I3244J0D01*
G01X1022600Y181774D02*
X1024600D01*
X1037616Y179480D01*
X1049828Y181633D01*
X1083810Y205428D01*
X1113261Y247489D01*
X1141101Y314413D01*
X1195292Y623376D01*
X1309981Y787171D01*
X1310139Y787668D01*
X1310177Y787687D01*
X1311346Y791376D01*
X1308679Y806500D01*
X1310892Y819051D01*
X1309981Y824219D01*
Y828007D01*
G03X1309031Y830301I-3244J0D01*
G01X1016141Y183071D02*
X1017092Y184021D01*
G03X1017460Y184911I-890J889D01*
G01Y184975D01*
G02X1018043Y186382I1990J0D01*
G01X1018580Y186919D01*
G02X1020707Y187800I2127J-2127D01*
G01X1037030Y184922D01*
G03X1037220I95J542D01*
G01X1050057Y187184D01*
G03X1050276Y187275I-96J541D01*
G01X1079460Y207709D01*
G03X1079595Y207844I-315J450D01*
G01X1111630Y253595D01*
X1128088Y293159D01*
X1185162Y616585D01*
X1276481Y747001D01*
X1286179Y802000D01*
X1283430Y817590D01*
X1284783Y825262D01*
Y828007D01*
G03X1283833Y830301I-3244J0D01*
G01X1271235D02*
G02X1272185Y828007I-2294J-2294D01*
G01Y825700D01*
X1270121Y814000D01*
X1274101Y791429D01*
X1266269Y747010D01*
X1172346Y612874D01*
X1110643Y262960D01*
X1074019Y210656D01*
X1046990Y191731D01*
X1041050Y190684D01*
X1024600Y193584D01*
X1022600D01*
G01X1258637Y830301D02*
G02X1259587Y828007I-2294J-2294D01*
G01Y826359D01*
X1258219Y818609D01*
X1259260Y812701D01*
X1264426Y805327D01*
X1264796Y803227D01*
X1265167Y801125D01*
X1265873Y797122D01*
X1266739Y792214D01*
X1267603Y787308D01*
X1262103Y756115D01*
X1170110Y624734D01*
X1106466Y263796D01*
X1071909Y214443D01*
X1045665Y196067D01*
X1040136Y195092D01*
X1026145Y197558D01*
X1023731D01*
G01X1246039Y830301D02*
G02X1246989Y828007I-2294J-2294D01*
G01Y826667D01*
X1247606Y823159D01*
X1246086Y814533D01*
X1250071Y791932D01*
X1245353Y765172D01*
X1169024Y656160D01*
X1099677Y262874D01*
X1068259Y218005D01*
X1044541Y201273D01*
X1042340Y199732D01*
X1027875Y201458D01*
X1022600D01*
G01X1023731Y209369D02*
X1026731D01*
X1038008Y207381D01*
X1045579Y208716D01*
X1064584Y222023D01*
X1092152Y261393D01*
X1162742Y661730D01*
X1227086Y753617D01*
X1235161Y799411D01*
X1232500Y814500D01*
X1234390Y825219D01*
Y828007D01*
G03X1233440Y830301I-3244J0D01*
G01X1022600Y211969D02*
X1029168D01*
X1037500Y210500D01*
X1042777Y211431D01*
X1060474Y223823D01*
X1086597Y261131D01*
X1158690Y669984D01*
X1216520Y752586D01*
X1224925Y800251D01*
X1222500Y814000D01*
X1223944Y822186D01*
X1223094Y827012D01*
X1223092Y827014D01*
Y828007D01*
G02X1224042Y830301I3244J0D01*
G01X1023192Y215943D02*
X1026617D01*
X1037504Y214023D01*
X1040776Y214600D01*
X1056818Y225833D01*
X1078867Y257322D01*
X1154415Y686321D01*
X1156763Y691334D01*
X1156768Y691344D01*
X1156803Y691423D01*
X1156804Y691426D01*
X1164357Y709730D01*
X1188046Y743564D01*
X1191528Y763312D01*
X1195000Y783000D01*
X1190444Y808839D01*
X1192463Y820290D01*
X1191595Y825212D01*
Y828007D01*
G02X1192545Y830301I3244J0D01*
G01X1179947D02*
G03X1178997Y828007I2294J-2294D01*
G01Y821186D01*
X1180000Y815500D01*
X1178076Y804591D01*
X1182500Y779500D01*
X1176069Y743026D01*
X1152150Y708866D01*
X1072711Y258338D01*
X1051084Y227452D01*
X1040362Y219945D01*
X1035000Y219000D01*
X1030219Y219843D01*
X1022600D01*
G01X1023192Y223817D02*
X1026617D01*
X1037545Y225744D01*
X1042950Y229529D01*
X1048306Y233279D01*
X1068232Y261736D01*
X1153243Y743859D01*
X1149541Y764858D01*
X1158602Y816250D01*
X1157746Y821106D01*
X1156950Y825625D01*
X1156949D01*
Y828007D01*
G02X1157899Y830301I3244J0D01*
G01X1022600Y227717D02*
X1027500D01*
X1035506Y229129D01*
X1040314Y232496D01*
X1045072Y235827D01*
X1063220Y261744D01*
X1143449Y716745D01*
X1137413Y750974D01*
X1147028Y805500D01*
X1144351Y820680D01*
Y828007D01*
G02X1145301Y830301I3244J0D01*
G01X1022627Y232051D02*
G03X1023681Y231700I1052J1402D01*
G01X1028364D01*
X1030970Y232159D01*
X1035339Y235219D01*
X1039660Y238244D01*
X1053740Y258353D01*
X1093797Y485564D01*
X1133843Y712715D01*
X1127637Y747916D01*
X1136109Y795969D01*
X1131753Y820670D01*
Y828007D01*
G02X1132703Y830301I3244J0D01*
G01X1024060Y236326D02*
X1037526Y245756D01*
X1047500Y260000D01*
X1127667Y714648D01*
X1116264Y779315D01*
X1120000Y800500D01*
X1117339Y815589D01*
X1119154Y825883D01*
Y828600D01*
G02X1119685Y829882I1813J0D01*
G01X1120104Y830301D01*
G01X1022600Y213269D02*
X1029282D01*
X1037500Y211821D01*
X1042267Y212662D01*
X1059540Y224757D01*
X1085366Y261641D01*
X1157459Y670494D01*
X1215289Y753096D01*
X1223604Y800251D01*
X1221179Y814000D01*
X1222623Y822186D01*
X1221794Y826898D01*
X1221792Y826900D01*
Y828007D01*
G03X1220842Y830301I-3244J0D01*
G01X1023731Y217243D02*
X1026731D01*
X1037504Y215344D01*
X1038887Y215588D01*
X1040266Y215831D01*
X1055884Y226767D01*
X1077636Y257832D01*
X1153164Y686717D01*
X1155585Y691887D01*
X1155586D01*
X1155595Y691906D01*
X1155598Y691913D01*
X1155600Y691917D01*
X1163209Y710359D01*
X1186815Y744074D01*
X1193679Y783000D01*
X1189123Y808839D01*
X1191142Y820290D01*
X1190295Y825098D01*
Y828007D01*
G03X1189345Y830301I-3244J0D01*
G01X1176747D02*
G02X1177697Y828007I-2294J-2294D01*
G01Y821068D01*
X1178679Y815500D01*
X1176755Y804591D01*
X1181179Y779500D01*
X1174838Y743536D01*
X1150919Y709376D01*
X1071480Y258848D01*
X1050150Y228386D01*
X1039852Y221176D01*
X1035000Y220321D01*
X1030333Y221143D01*
X1022600D01*
G01X1023731Y225117D02*
X1026503D01*
X1037035Y226975D01*
X1047372Y234213D01*
X1067001Y262246D01*
X1151922Y743859D01*
X1148220Y764858D01*
X1157281Y816250D01*
X1155649Y825509D01*
Y828007D01*
G03X1154699Y830301I-3244J0D01*
G01X1022600Y229017D02*
X1027386D01*
X1034996Y230360D01*
X1044138Y236761D01*
X1061989Y262254D01*
X1142128Y716745D01*
X1136092Y750974D01*
X1145707Y805500D01*
X1143051Y820561D01*
Y828007D01*
G03X1142101Y830301I-3244J0D01*
G01X1023378Y233113D02*
X1023407Y233091D01*
G03X1023680Y233000I272J362D01*
G01X1028250D01*
X1030460Y233390D01*
X1038726Y239178D01*
X1052509Y258863D01*
X1132522Y712715D01*
X1129459Y730090D01*
X1126316Y747916D01*
X1134788Y795969D01*
X1130453Y820556D01*
Y828007D01*
G03X1129503Y830301I-3244J0D01*
G01X1022600Y236891D02*
X1036592Y246690D01*
X1046269Y260510D01*
X1126346Y714648D01*
X1114943Y779315D01*
X1118679Y800500D01*
X1116018Y815589D01*
X1117854Y826000D01*
Y828007D01*
G03X1116904Y830301I-3244J0D01*
G01X1014800Y263500D02*
Y267285D01*
X1015431Y270865D01*
X1046981Y315924D01*
X1114336Y697909D01*
X1100110Y778591D01*
X1107617Y821161D01*
X1106556Y827175D01*
Y828007D01*
G02X1107506Y830301I3244J0D01*
G01X1010800Y263600D02*
Y267284D01*
X1011079Y268871D01*
X1011359Y270459D01*
X1011954Y273832D01*
X1040327Y314354D01*
X1074321Y507143D01*
X1108304Y699871D01*
X1091987Y792411D01*
X1095860Y814376D01*
X1093957Y825162D01*
Y828007D01*
G02X1094907Y830301I3244J0D01*
G01X1013500Y263500D02*
Y267399D01*
X1014200Y271375D01*
X1045750Y316434D01*
X1113015Y697909D01*
X1098789Y778591D01*
X1102583Y800102D01*
X1106296Y821161D01*
X1105256Y827061D01*
Y828007D01*
G03X1104306Y830301I-3244J0D01*
G01X1009500Y263600D02*
Y267398D01*
X1010078Y270685D01*
X1010723Y274342D01*
X1039096Y314864D01*
X1106983Y699871D01*
X1090666Y792411D01*
X1094539Y814376D01*
X1092657Y825048D01*
Y828007D01*
G03X1091707Y830301I-3244J0D01*
G54D16*
X1126513Y69803D03*
Y84764D03*
X1129466Y79252D03*
X1169820Y69803D03*
X1213128D03*
X1256435D03*
G54D17*
G01X649400Y234500D02*
X698199D01*
X703900Y240201D01*
Y300900D01*
X713000Y310000D01*
G01X1226000Y261300D02*
X1221300Y266000D01*
Y300500D01*
X1228500Y307700D01*
X1294600D01*
X1309900Y292400D01*
G54D18*
G01X980708Y139764D02*
X978758Y137814D01*
Y131082D01*
X980708Y129132D01*
Y127953D01*
G01X1327300Y319100D02*
Y292200D01*
X1312200Y277100D01*
Y275200D01*
G54D19*
G01X112700Y766300D02*
X124314Y754686D01*
Y718631D01*
X107283Y701600D01*
X63100D01*
X59100Y705600D01*
M02*
